FILE_TYPE = MACRO_DRAWING;
SET COLOR_WIRE YELLOW;
SET COLOR_PROP MONO;
SET COLOR_DOT WHITE;
SET COLOR_ARC YELLOW;
SET COLOR_BODY GREEN;
SET COLOR_NOTE MONO;
SET PROP_DISPLAY VALUE;
SET PAGE_NUMBER P181;
FORCEADD OFFPAGE..1
(-2850 1550);
FORCEPROP 2 LAST $XR0 181 
J 0
(-3102 1550);
DISPLAY 0.638298 (-3102 1550);
PAINT MONO (-3102 1550);
FORCEPROP 2 LAST PATH I1
J 0
(-3100 1600);
DISPLAY 1.021277 (-3100 1600);
PAINT ORANGE (-3100 1600);
DISPLAY INVISIBLE (-3100 1600);
FORCEPROP 2 LAST CDS_LIB mstr_standard
J 0
(-2850 1550);
PAINT ORANGE (-2850 1550);
DISPLAY INVISIBLE (-2850 1550);
FORCEPROP 1 LAST OFFPAGE TRUE
J 0
(-2525 1425);
DISPLAY 0.872340 (-2525 1425);
PAINT GREEN (-2525 1425);
DISPLAY INVISIBLE (-2525 1425);
FORCEPROP 1 LAST COMMENT_BODY TRUE
J 0
(-2725 1450);
DISPLAY 0.872340 (-2725 1450);
PAINT GREEN (-2725 1450);
DISPLAY INVISIBLE (-2725 1450);
FORCEADD OFFPAGE..6
(-2875 2375);
FORCEPROP 2 LAST $XR0 182 
J 0
(-3185 2375);
DISPLAY 0.638298 (-3185 2375);
PAINT MONO (-3185 2375);
FORCEPROP 2 LAST PATH I10
J 0
(-3175 2425);
DISPLAY 1.021277 (-3175 2425);
PAINT ORANGE (-3175 2425);
DISPLAY INVISIBLE (-3175 2425);
FORCEPROP 2 LAST CDS_LIB mstr_standard
J 0
(-2875 2375);
PAINT ORANGE (-2875 2375);
DISPLAY INVISIBLE (-2875 2375);
FORCEPROP 1 LAST OFFPAGE TRUE
J 0
(-2550 2250);
DISPLAY 0.872340 (-2550 2250);
PAINT GREEN (-2550 2250);
DISPLAY INVISIBLE (-2550 2250);
FORCEPROP 1 LAST COMMENT_BODY TRUE
J 0
(-2775 2300);
DISPLAY 0.872340 (-2775 2300);
PAINT GREEN (-2775 2300);
DISPLAY INVISIBLE (-2775 2300);
FORCEADD OFFPAGE..3
R 2
(2900 1100);
FORCEPROP 2 LAST $XR4 247 
J 0
(2140 1100);
DISPLAY 0.638298 (2140 1100);
PAINT MONO (2140 1100);
FORCEPROP 2 LAST $XR3 199 
J 0
(2260 1100);
DISPLAY 0.638298 (2260 1100);
PAINT MONO (2260 1100);
FORCEPROP 2 LAST $XR2 181 
J 0
(2380 1100);
DISPLAY 0.638298 (2380 1100);
PAINT MONO (2380 1100);
FORCEPROP 2 LAST $XR1 159 
J 0
(2500 1100);
DISPLAY 0.638298 (2500 1100);
PAINT MONO (2500 1100);
FORCEPROP 2 LAST $XR0 138 
J 0
(2620 1100);
DISPLAY 0.638298 (2620 1100);
PAINT MONO (2620 1100);
FORCEPROP 2 LAST PATH I100
J 0
(2625 1150);
DISPLAY 1.021277 (2625 1150);
PAINT ORANGE (2625 1150);
DISPLAY INVISIBLE (2625 1150);
FORCEPROP 2 LAST CDS_LIB mstr_standard
J 2
(2900 1100);
PAINT ORANGE (2900 1100);
DISPLAY INVISIBLE (2900 1100);
FORCEPROP 1 LAST OFFPAGE TRUE
J 2
(2575 975);
DISPLAY 0.872340 (2575 975);
PAINT GREEN (2575 975);
DISPLAY INVISIBLE (2575 975);
FORCEPROP 1 LAST COMMENT_BODY TRUE
J 2
(2950 1000);
DISPLAY 0.872340 (2950 1000);
PAINT GREEN (2950 1000);
DISPLAY INVISIBLE (2950 1000);
FORCEADD OFFPAGE..5
(2900 1250);
FORCEPROP 2 LAST $XR3 190 
J 0
(2255 1250);
DISPLAY 0.638298 (2255 1250);
PAINT MONO (2255 1250);
FORCEPROP 2 LAST $XR2 144 
J 0
(2375 1250);
DISPLAY 0.638298 (2375 1250);
PAINT MONO (2375 1250);
FORCEPROP 2 LAST $XR1 120 
J 0
(2495 1250);
DISPLAY 0.638298 (2495 1250);
PAINT MONO (2495 1250);
FORCEPROP 2 LAST $XR0 157 
J 0
(2615 1250);
DISPLAY 0.638298 (2615 1250);
PAINT MONO (2615 1250);
FORCEPROP 2 LAST PATH I101
J 0
(2625 1300);
DISPLAY 1.021277 (2625 1300);
PAINT ORANGE (2625 1300);
DISPLAY INVISIBLE (2625 1300);
FORCEPROP 2 LAST CDS_LIB mstr_standard
J 0
(2900 1250);
PAINT MONO (2900 1250);
DISPLAY INVISIBLE (2900 1250);
FORCEPROP 1 LAST OFFPAGE TRUE
J 0
(3225 1125);
DISPLAY 0.872340 (3225 1125);
PAINT GREEN (3225 1125);
DISPLAY INVISIBLE (3225 1125);
FORCEPROP 1 LAST COMMENT_BODY TRUE
J 0
(3000 1175);
DISPLAY 0.872340 (3000 1175);
PAINT GREEN (3000 1175);
DISPLAY INVISIBLE (3000 1175);
FORCEADD OFFPAGE..1
(2900 1200);
FORCEPROP 2 LAST $XR0 181 
J 0
(2618 1200);
DISPLAY 0.638298 (2618 1200);
PAINT MONO (2618 1200);
FORCEPROP 2 LAST PATH I102
J 0
(2625 1250);
DISPLAY 1.021277 (2625 1250);
PAINT ORANGE (2625 1250);
DISPLAY INVISIBLE (2625 1250);
FORCEPROP 2 LAST CDS_LIB mstr_standard
J 0
(2900 1200);
PAINT ORANGE (2900 1200);
DISPLAY INVISIBLE (2900 1200);
FORCEPROP 1 LAST OFFPAGE TRUE
J 0
(3225 1075);
DISPLAY 0.872340 (3225 1075);
PAINT GREEN (3225 1075);
DISPLAY INVISIBLE (3225 1075);
FORCEPROP 1 LAST COMMENT_BODY TRUE
J 0
(3025 1100);
DISPLAY 0.872340 (3025 1100);
PAINT GREEN (3025 1100);
DISPLAY INVISIBLE (3025 1100);
FORCEADD OFFPAGE..5
(2900 1300);
FORCEPROP 2 LAST $XR2 120 
J 0
(2375 1300);
DISPLAY 0.638298 (2375 1300);
PAINT MONO (2375 1300);
FORCEPROP 2 LAST $XR1 157 
J 0
(2495 1300);
DISPLAY 0.638298 (2495 1300);
PAINT MONO (2495 1300);
FORCEPROP 2 LAST $XR0 146 
J 0
(2615 1300);
DISPLAY 0.638298 (2615 1300);
PAINT MONO (2615 1300);
FORCEPROP 2 LAST PATH I103
J 0
(2625 1350);
DISPLAY 1.021277 (2625 1350);
PAINT ORANGE (2625 1350);
DISPLAY INVISIBLE (2625 1350);
FORCEPROP 2 LAST CDS_LIB mstr_standard
J 0
(2900 1300);
PAINT MONO (2900 1300);
DISPLAY INVISIBLE (2900 1300);
FORCEPROP 1 LAST OFFPAGE TRUE
J 0
(3225 1175);
DISPLAY 0.872340 (3225 1175);
PAINT GREEN (3225 1175);
DISPLAY INVISIBLE (3225 1175);
FORCEPROP 1 LAST COMMENT_BODY TRUE
J 0
(3000 1225);
DISPLAY 0.872340 (3000 1225);
PAINT GREEN (3000 1225);
DISPLAY INVISIBLE (3000 1225);
FORCEADD GND..1
(3650 800);
FORCEPROP 3 LASTPIN (3650 850) SIG_NAME GND\g
J 0
(3660 860);
DISPLAY 0.659574 (3660 860);
PAINT MONO (3660 860);
DISPLAY INVISIBLE (3660 860);
FORCEPROP 1 LAST PATH I104
J 0
(3725 800);
DISPLAY 0.872340 (3725 800);
PAINT AQUA (3725 800);
DISPLAY INVISIBLE (3725 800);
FORCEPROP 2 LAST BOM_COST NT_BASE_VRD
J 0
(3350 875);
DISPLAY 0.617021 (3350 875);
PAINT ORANGE (3350 875);
DISPLAY INVISIBLE (3350 875);
FORCEPROP 2 LAST ROOM P2V5_LAN_AUX_VR
J 0
(3350 875);
DISPLAY 0.617021 (3350 875);
PAINT ORANGE (3350 875);
DISPLAY INVISIBLE (3350 875);
FORCEPROP 2 LAST CDS_LIB mstr_symbols
J 0
(3650 800);
PAINT ORANGE (3650 800);
DISPLAY INVISIBLE (3650 800);
FORCEPROP 1 LAST VOLTAGE 0
J 0
(3650 800);
PAINT SKYBLUE (3650 800);
DISPLAY INVISIBLE (3650 800);
FORCEPROP 1 LAST SIZE 1B
J 0
(3725 750);
DISPLAY 0.872340 (3725 750);
PAINT GREEN (3725 750);
DISPLAY INVISIBLE (3725 750);
FORCEPROP 1 LAST BODY_TYPE PLUMBING
J 0
(3605 757);
DISPLAY 0.340426 (3605 757);
PAINT GREEN (3605 757);
DISPLAY INVISIBLE (3605 757);
FORCEPROP 1 LAST HDL_POWER GND
J 0
(3650 950);
DISPLAY 0.872340 (3650 950);
PAINT GREEN (3650 950);
DISPLAY INVISIBLE (3650 950);
FORCEADD P3V3_STBY..1
(3650 1600);
FORCEPROP 3 LASTPIN (3650 1550) SIG_NAME P3V3_STBY\g
J 0
(3660 1560);
DISPLAY 0.659574 (3660 1560);
PAINT MONO (3660 1560);
DISPLAY INVISIBLE (3660 1560);
FORCEPROP 1 LAST PATH I105
J 0
(3695 1602);
DISPLAY 0.340426 (3695 1602);
PAINT GREEN (3695 1602);
DISPLAY INVISIBLE (3695 1602);
FORCEPROP 2 LAST CDS_LIB mstr_symbols
J 0
(3650 1600);
PAINT ORANGE (3650 1600);
DISPLAY INVISIBLE (3650 1600);
FORCEPROP 1 LAST VOLTAGE 3.3V
J 0
(3605 1557);
DISPLAY 0.340426 (3605 1557);
PAINT SKYBLUE (3605 1557);
DISPLAY INVISIBLE (3605 1557);
FORCEPROP 1 LAST SIZE 1B
J 0
(3695 1622);
DISPLAY 0.340426 (3695 1622);
PAINT GREEN (3695 1622);
DISPLAY INVISIBLE (3695 1622);
FORCEPROP 1 LAST BODY_TYPE PLUMBING
J 0
(3605 1557);
DISPLAY 0.340426 (3605 1557);
PAINT GREEN (3605 1557);
DISPLAY INVISIBLE (3605 1557);
FORCEPROP 1 LAST HDL_POWER P3V3_STBY
J 0
(3350 1475);
DISPLAY 0.872340 (3350 1475);
PAINT ORANGE (3350 1475);
DISPLAY INVISIBLE (3350 1475);
FORCEADD CONN8_H62179001..1
(4100 1250);
FORCEPROP 2 LASTPIN (3900 1350) $PN 1
J 2
(3890 1360);
DISPLAY 0.617021 (3890 1360);
PAINT MONO (3890 1360);
FORCEPROP 2 LASTPIN (3900 1000) $PN 8
J 2
(3890 1010);
DISPLAY 0.617021 (3890 1010);
PAINT MONO (3890 1010);
FORCEPROP 2 LASTPIN (3900 1200) $PN 4
J 2
(3890 1210);
DISPLAY 0.617021 (3890 1210);
PAINT MONO (3890 1210);
FORCEPROP 2 LASTPIN (3900 1150) $PN 5
J 2
(3890 1160);
DISPLAY 0.617021 (3890 1160);
PAINT MONO (3890 1160);
FORCEPROP 2 LASTPIN (3900 1100) $PN 6
J 2
(3890 1110);
DISPLAY 0.617021 (3890 1110);
PAINT MONO (3890 1110);
FORCEPROP 2 LASTPIN (3900 1050) $PN 7
J 2
(3890 1060);
DISPLAY 0.617021 (3890 1060);
PAINT MONO (3890 1060);
FORCEPROP 2 LASTPIN (3900 1250) $PN 3
J 2
(3890 1260);
DISPLAY 0.617021 (3890 1260);
PAINT MONO (3890 1260);
FORCEPROP 2 LASTPIN (3900 1300) $PN 2
J 2
(3890 1310);
DISPLAY 0.617021 (3890 1310);
PAINT MONO (3890 1310);
FORCEPROP 1 LAST MATERIAL CONN
J 0
(3950 1600);
DISPLAY 0.617021 (3950 1600);
PAINT SKYBLUE (3950 1600);
FORCEPROP 1 LAST LOCATION J1F3
J 0
(3950 1675);
DISPLAY 0.617021 (3950 1675);
PAINT AQUA (3950 1675);
FORCEPROP 0 LAST POP NOPOP
J 0
(3950 850);
DISPLAY 0.638298 (3950 850);
PAINT RED (3950 850);
FORCEPROP 1 LAST PART_NUMBER H62179-001
J 0
(3950 900);
DISPLAY 0.617021 (3950 900);
PAINT BLUE (3950 900);
FORCEPROP 1 LAST PATH I106
J 0
(4125 1600);
PAINT GREEN (4125 1600);
DISPLAY INVISIBLE (4125 1600);
FORCEPROP 2 LAST CDS_LIB mstr_conn
J 0
(4100 1250);
PAINT ORANGE (4100 1250);
DISPLAY INVISIBLE (4100 1250);
FORCEPROP 2 LAST CDS_SEC 1
J 0
(4000 1725);
PAINT MONO (4000 1725);
DISPLAY INVISIBLE (4000 1725);
FORCEPROP 2 LAST $SEC 1
J 0
(4000 1725);
PAINT MONO (4000 1725);
DISPLAY INVISIBLE (4000 1725);
FORCEPROP 2 LAST CDS_LOCATION J1F3
J 0
(4000 1675);
DISPLAY 0.617021 (4000 1675);
PAINT AQUA (4000 1675);
DISPLAY INVISIBLE (4000 1675);
FORCEPROP 0 LAST ROOM IO_SLOT
J 2
(4050 1725);
DISPLAY 0.617021 (4050 1725);
PAINT ORANGE (4050 1725);
DISPLAY INVISIBLE (4050 1725);
FORCEPROP 1 LAST PACK_TYPE PIP
J 0
(3950 1700);
PAINT SKYBLUE (3950 1700);
DISPLAY INVISIBLE (3950 1700);
FORCEADD TAP..6
R 2
(3175 2750);
FORCEPROP 3 LASTPIN (3125 2750) SIG_NAME P3E_CPU1_PE3_MP_TXN<1>
J 0
(3135 2760);
DISPLAY 0.659574 (3135 2760);
PAINT MONO (3135 2760);
DISPLAY INVISIBLE (3135 2760);
FORCEPROP 1 LASTPIN (3125 2750) BN 1
J 2
(3177 2758);
DISPLAY 0.617021 (3177 2758);
PAINT GREEN (3177 2758);
FORCEPROP 1 LAST PATH I107
J 2
(3177 2750);
DISPLAY 0.872340 (3177 2750);
PAINT GREEN (3177 2750);
DISPLAY INVISIBLE (3177 2750);
FORCEPROP 2 LAST CDS_LIB mstr_standard
J 0
(3175 2750);
PAINT ORANGE (3175 2750);
DISPLAY INVISIBLE (3175 2750);
FORCEPROP 1 LAST BODY_TYPE PLUMBING
J 2
(3175 2700);
DISPLAY 1.234043 (3175 2700);
PAINT GREEN (3175 2700);
DISPLAY INVISIBLE (3175 2700);
FORCEPROP 1 LAST HDL_TAP TRUE
J 2
(2850 2625);
DISPLAY 1.234043 (2850 2625);
PAINT GREEN (2850 2625);
DISPLAY INVISIBLE (2850 2625);
FORCEADD TAP..6
R 2
(3175 2600);
FORCEPROP 3 LASTPIN (3125 2600) SIG_NAME P3E_CPU1_PE3_MP_TXN<2>
J 0
(3135 2610);
DISPLAY 0.659574 (3135 2610);
PAINT MONO (3135 2610);
DISPLAY INVISIBLE (3135 2610);
FORCEPROP 1 LASTPIN (3125 2600) BN 2
J 2
(3177 2608);
DISPLAY 0.617021 (3177 2608);
PAINT GREEN (3177 2608);
FORCEPROP 1 LAST PATH I108
J 2
(3177 2600);
DISPLAY 0.872340 (3177 2600);
PAINT GREEN (3177 2600);
DISPLAY INVISIBLE (3177 2600);
FORCEPROP 2 LAST CDS_LIB mstr_standard
J 0
(3175 2600);
PAINT ORANGE (3175 2600);
DISPLAY INVISIBLE (3175 2600);
FORCEPROP 1 LAST BODY_TYPE PLUMBING
J 2
(3175 2550);
DISPLAY 1.234043 (3175 2550);
PAINT GREEN (3175 2550);
DISPLAY INVISIBLE (3175 2550);
FORCEPROP 1 LAST HDL_TAP TRUE
J 2
(2850 2475);
DISPLAY 1.234043 (2850 2475);
PAINT GREEN (2850 2475);
DISPLAY INVISIBLE (2850 2475);
FORCEADD OFFPAGE..2
(3275 1875);
FORCEPROP 2 LAST $XR2 164 
J 0
(3704 1875);
DISPLAY 0.638298 (3704 1875);
PAINT MONO (3704 1875);
FORCEPROP 2 LAST $XR1 119 
J 0
(3584 1875);
DISPLAY 0.638298 (3584 1875);
PAINT MONO (3584 1875);
FORCEPROP 2 LAST $XR0 181 
J 0
(3464 1875);
DISPLAY 0.638298 (3464 1875);
PAINT MONO (3464 1875);
FORCEPROP 2 LAST PATH I109
J 0
(3725 1925);
DISPLAY 1.021277 (3725 1925);
PAINT ORANGE (3725 1925);
DISPLAY INVISIBLE (3725 1925);
FORCEPROP 2 LAST CDS_LIB mstr_standard
J 0
(3275 1875);
PAINT ORANGE (3275 1875);
DISPLAY INVISIBLE (3275 1875);
FORCEPROP 1 LAST OFFPAGE TRUE
J 0
(3600 1750);
DISPLAY 0.872340 (3600 1750);
PAINT GREEN (3600 1750);
DISPLAY INVISIBLE (3600 1750);
FORCEPROP 1 LAST COMMENT_BODY TRUE
J 0
(3230 1780);
DISPLAY 0.872340 (3230 1780);
PAINT GREEN (3230 1780);
DISPLAY INVISIBLE (3230 1780);
FORCEADD OFFPAGE..5
(-2925 2800);
FORCEPROP 2 LAST $XR1 147 
J 0
(-3300 2800);
DISPLAY 0.638298 (-3300 2800);
PAINT MONO (-3300 2800);
FORCEPROP 2 LAST $XR0 161 
J 0
(-3180 2800);
DISPLAY 0.638298 (-3180 2800);
PAINT MONO (-3180 2800);
FORCEPROP 2 LAST PATH I11
J 0
(-3175 2850);
DISPLAY 1.021277 (-3175 2850);
PAINT ORANGE (-3175 2850);
DISPLAY INVISIBLE (-3175 2850);
FORCEPROP 2 LAST CDS_LIB mstr_standard
J 0
(-2925 2800);
PAINT ORANGE (-2925 2800);
DISPLAY INVISIBLE (-2925 2800);
FORCEPROP 1 LAST OFFPAGE TRUE
J 0
(-2600 2675);
DISPLAY 0.872340 (-2600 2675);
PAINT GREEN (-2600 2675);
DISPLAY INVISIBLE (-2600 2675);
FORCEPROP 1 LAST COMMENT_BODY TRUE
J 0
(-2825 2725);
DISPLAY 0.872340 (-2825 2725);
PAINT GREEN (-2825 2725);
DISPLAY INVISIBLE (-2825 2725);
FORCEADD OFFPAGE..2
(3275 2050);
FORCEPROP 2 LAST $XR2 164 
J 0
(3704 2050);
DISPLAY 0.638298 (3704 2050);
PAINT MONO (3704 2050);
FORCEPROP 2 LAST $XR1 119 
J 0
(3584 2050);
DISPLAY 0.638298 (3584 2050);
PAINT MONO (3584 2050);
FORCEPROP 2 LAST $XR0 181 
J 0
(3464 2050);
DISPLAY 0.638298 (3464 2050);
PAINT MONO (3464 2050);
FORCEPROP 2 LAST PATH I110
J 0
(3725 2100);
DISPLAY 1.021277 (3725 2100);
PAINT ORANGE (3725 2100);
DISPLAY INVISIBLE (3725 2100);
FORCEPROP 2 LAST CDS_LIB mstr_standard
J 0
(3275 2050);
PAINT ORANGE (3275 2050);
DISPLAY INVISIBLE (3275 2050);
FORCEPROP 1 LAST OFFPAGE TRUE
J 0
(3600 1925);
DISPLAY 0.872340 (3600 1925);
PAINT GREEN (3600 1925);
DISPLAY INVISIBLE (3600 1925);
FORCEPROP 1 LAST COMMENT_BODY TRUE
J 0
(3230 1955);
DISPLAY 0.872340 (3230 1955);
PAINT GREEN (3230 1955);
DISPLAY INVISIBLE (3230 1955);
FORCEADD OFFPAGE..2
(3275 2225);
FORCEPROP 2 LAST $XR2 164 
J 0
(3704 2225);
DISPLAY 0.638298 (3704 2225);
PAINT MONO (3704 2225);
FORCEPROP 2 LAST $XR1 119 
J 0
(3584 2225);
DISPLAY 0.638298 (3584 2225);
PAINT MONO (3584 2225);
FORCEPROP 2 LAST $XR0 181 
J 0
(3464 2225);
DISPLAY 0.638298 (3464 2225);
PAINT MONO (3464 2225);
FORCEPROP 2 LAST PATH I111
J 0
(3725 2275);
DISPLAY 1.021277 (3725 2275);
PAINT ORANGE (3725 2275);
DISPLAY INVISIBLE (3725 2275);
FORCEPROP 2 LAST CDS_LIB mstr_standard
J 0
(3275 2225);
PAINT ORANGE (3275 2225);
DISPLAY INVISIBLE (3275 2225);
FORCEPROP 1 LAST OFFPAGE TRUE
J 0
(3600 2100);
DISPLAY 0.872340 (3600 2100);
PAINT GREEN (3600 2100);
DISPLAY INVISIBLE (3600 2100);
FORCEPROP 1 LAST COMMENT_BODY TRUE
J 0
(3230 2130);
DISPLAY 0.872340 (3230 2130);
PAINT GREEN (3230 2130);
DISPLAY INVISIBLE (3230 2130);
FORCEADD TAP..6
R 2
(3175 2900);
FORCEPROP 3 LASTPIN (3125 2900) SIG_NAME P3E_CPU1_PE3_MP_TXN<0>
J 0
(3135 2910);
DISPLAY 0.659574 (3135 2910);
PAINT MONO (3135 2910);
DISPLAY INVISIBLE (3135 2910);
FORCEPROP 1 LASTPIN (3125 2900) BN 0
J 2
(3177 2908);
DISPLAY 0.617021 (3177 2908);
PAINT GREEN (3177 2908);
FORCEPROP 1 LAST PATH I112
J 2
(3177 2900);
DISPLAY 0.872340 (3177 2900);
PAINT GREEN (3177 2900);
DISPLAY INVISIBLE (3177 2900);
FORCEPROP 2 LAST CDS_LIB mstr_standard
J 0
(3175 2900);
PAINT ORANGE (3175 2900);
DISPLAY INVISIBLE (3175 2900);
FORCEPROP 1 LAST BODY_TYPE PLUMBING
J 2
(3175 2850);
DISPLAY 1.234043 (3175 2850);
PAINT GREEN (3175 2850);
DISPLAY INVISIBLE (3175 2850);
FORCEPROP 1 LAST HDL_TAP TRUE
J 2
(2850 2775);
DISPLAY 1.234043 (2850 2775);
PAINT GREEN (2850 2775);
DISPLAY INVISIBLE (2850 2775);
FORCEADD TAP..6
R 2
(3175 3100);
FORCEPROP 3 LASTPIN (3125 3100) SIG_NAME P3E_CPU1_PE3_MP_TXN<5>
J 0
(3135 3110);
DISPLAY 0.659574 (3135 3110);
PAINT MONO (3135 3110);
DISPLAY INVISIBLE (3135 3110);
FORCEPROP 1 LASTPIN (3125 3100) BN 5
J 2
(3177 3108);
DISPLAY 0.617021 (3177 3108);
PAINT GREEN (3177 3108);
FORCEPROP 1 LAST PATH I113
J 2
(3177 3100);
DISPLAY 0.872340 (3177 3100);
PAINT GREEN (3177 3100);
DISPLAY INVISIBLE (3177 3100);
FORCEPROP 2 LAST CDS_LIB mstr_standard
J 0
(3175 3100);
PAINT ORANGE (3175 3100);
DISPLAY INVISIBLE (3175 3100);
FORCEPROP 1 LAST BODY_TYPE PLUMBING
J 2
(3175 3050);
DISPLAY 1.234043 (3175 3050);
PAINT GREEN (3175 3050);
DISPLAY INVISIBLE (3175 3050);
FORCEPROP 1 LAST HDL_TAP TRUE
J 2
(2850 2975);
DISPLAY 1.234043 (2850 2975);
PAINT GREEN (2850 2975);
DISPLAY INVISIBLE (2850 2975);
FORCEADD TAP..6
R 2
(3175 3300);
FORCEPROP 3 LASTPIN (3125 3300) SIG_NAME P3E_CPU1_PE3_MP_TXN<4>
J 0
(3135 3310);
DISPLAY 0.659574 (3135 3310);
PAINT MONO (3135 3310);
DISPLAY INVISIBLE (3135 3310);
FORCEPROP 1 LASTPIN (3125 3300) BN 4
J 2
(3177 3308);
DISPLAY 0.617021 (3177 3308);
PAINT GREEN (3177 3308);
FORCEPROP 1 LAST PATH I114
J 2
(3177 3300);
DISPLAY 0.872340 (3177 3300);
PAINT GREEN (3177 3300);
DISPLAY INVISIBLE (3177 3300);
FORCEPROP 2 LAST CDS_LIB mstr_standard
J 0
(3175 3300);
PAINT ORANGE (3175 3300);
DISPLAY INVISIBLE (3175 3300);
FORCEPROP 1 LAST BODY_TYPE PLUMBING
J 2
(3175 3250);
DISPLAY 1.234043 (3175 3250);
PAINT GREEN (3175 3250);
DISPLAY INVISIBLE (3175 3250);
FORCEPROP 1 LAST HDL_TAP TRUE
J 2
(2850 3175);
DISPLAY 1.234043 (2850 3175);
PAINT GREEN (2850 3175);
DISPLAY INVISIBLE (2850 3175);
FORCEADD TAP..6
R 2
(3175 3450);
FORCEPROP 3 LASTPIN (3125 3450) SIG_NAME P3E_CPU1_PE3_MP_TXN<3>
J 0
(3135 3460);
DISPLAY 0.659574 (3135 3460);
PAINT MONO (3135 3460);
DISPLAY INVISIBLE (3135 3460);
FORCEPROP 1 LASTPIN (3125 3450) BN 3
J 2
(3177 3458);
DISPLAY 0.617021 (3177 3458);
PAINT GREEN (3177 3458);
FORCEPROP 1 LAST PATH I115
J 2
(3177 3450);
DISPLAY 0.872340 (3177 3450);
PAINT GREEN (3177 3450);
DISPLAY INVISIBLE (3177 3450);
FORCEPROP 2 LAST CDS_LIB mstr_standard
J 0
(3175 3450);
PAINT ORANGE (3175 3450);
DISPLAY INVISIBLE (3175 3450);
FORCEPROP 1 LAST BODY_TYPE PLUMBING
J 2
(3175 3400);
DISPLAY 1.234043 (3175 3400);
PAINT GREEN (3175 3400);
DISPLAY INVISIBLE (3175 3400);
FORCEPROP 1 LAST HDL_TAP TRUE
J 2
(2850 3325);
DISPLAY 1.234043 (2850 3325);
PAINT GREEN (2850 3325);
DISPLAY INVISIBLE (2850 3325);
FORCEADD TAP..6
R 2
(3175 3600);
FORCEPROP 3 LASTPIN (3125 3600) SIG_NAME P3E_CPU1_PE3_MP_TXN<7>
J 0
(3135 3610);
DISPLAY 0.659574 (3135 3610);
PAINT MONO (3135 3610);
DISPLAY INVISIBLE (3135 3610);
FORCEPROP 1 LASTPIN (3125 3600) BN 7
J 2
(3177 3608);
DISPLAY 0.617021 (3177 3608);
PAINT GREEN (3177 3608);
FORCEPROP 1 LAST PATH I116
J 2
(3177 3600);
DISPLAY 0.872340 (3177 3600);
PAINT GREEN (3177 3600);
DISPLAY INVISIBLE (3177 3600);
FORCEPROP 2 LAST CDS_LIB mstr_standard
J 0
(3175 3600);
PAINT ORANGE (3175 3600);
DISPLAY INVISIBLE (3175 3600);
FORCEPROP 1 LAST BODY_TYPE PLUMBING
J 2
(3175 3550);
DISPLAY 1.234043 (3175 3550);
PAINT GREEN (3175 3550);
DISPLAY INVISIBLE (3175 3550);
FORCEPROP 1 LAST HDL_TAP TRUE
J 2
(2850 3475);
DISPLAY 1.234043 (2850 3475);
PAINT GREEN (2850 3475);
DISPLAY INVISIBLE (2850 3475);
FORCEADD TAP..6
R 2
(3175 3800);
FORCEPROP 3 LASTPIN (3125 3800) SIG_NAME P3E_CPU1_PE3_MP_TXN<6>
J 0
(3135 3810);
DISPLAY 0.659574 (3135 3810);
PAINT MONO (3135 3810);
DISPLAY INVISIBLE (3135 3810);
FORCEPROP 1 LASTPIN (3125 3800) BN 6
J 2
(3177 3808);
DISPLAY 0.617021 (3177 3808);
PAINT GREEN (3177 3808);
FORCEPROP 1 LAST PATH I117
J 2
(3177 3800);
DISPLAY 0.872340 (3177 3800);
PAINT GREEN (3177 3800);
DISPLAY INVISIBLE (3177 3800);
FORCEPROP 2 LAST CDS_LIB mstr_standard
J 0
(3175 3800);
PAINT ORANGE (3175 3800);
DISPLAY INVISIBLE (3175 3800);
FORCEPROP 1 LAST BODY_TYPE PLUMBING
J 2
(3175 3750);
DISPLAY 1.234043 (3175 3750);
PAINT GREEN (3175 3750);
DISPLAY INVISIBLE (3175 3750);
FORCEPROP 1 LAST HDL_TAP TRUE
J 2
(2850 3675);
DISPLAY 1.234043 (2850 3675);
PAINT GREEN (2850 3675);
DISPLAY INVISIBLE (2850 3675);
FORCEADD OFFPAGE..3
(2000 3950);
FORCEPROP 2 LAST $XR4 247 
J 0
(2694 3950);
DISPLAY 0.638298 (2694 3950);
PAINT MONO (2694 3950);
FORCEPROP 2 LAST $XR3 199 
J 0
(2574 3950);
DISPLAY 0.638298 (2574 3950);
PAINT MONO (2574 3950);
FORCEPROP 2 LAST $XR2 181 
J 0
(2454 3950);
DISPLAY 0.638298 (2454 3950);
PAINT MONO (2454 3950);
FORCEPROP 2 LAST $XR1 159 
J 0
(2334 3950);
DISPLAY 0.638298 (2334 3950);
PAINT MONO (2334 3950);
FORCEPROP 2 LAST $XR0 138 
J 0
(2214 3950);
DISPLAY 0.638298 (2214 3950);
PAINT MONO (2214 3950);
FORCEPROP 2 LAST PATH I118
J 0
(2700 4000);
DISPLAY 1.021277 (2700 4000);
PAINT ORANGE (2700 4000);
DISPLAY INVISIBLE (2700 4000);
FORCEPROP 2 LAST CDS_LIB mstr_standard
J 0
(2000 3950);
PAINT ORANGE (2000 3950);
DISPLAY INVISIBLE (2000 3950);
FORCEPROP 1 LAST OFFPAGE TRUE
J 0
(2325 3825);
DISPLAY 0.872340 (2325 3825);
PAINT GREEN (2325 3825);
DISPLAY INVISIBLE (2325 3825);
FORCEPROP 1 LAST COMMENT_BODY TRUE
J 0
(1950 3850);
DISPLAY 0.872340 (1950 3850);
PAINT GREEN (1950 3850);
DISPLAY INVISIBLE (1950 3850);
FORCEADD OFFPAGE..2
(2000 4000);
FORCEPROP 2 LAST $XR1 199 
J 0
(2309 4000);
DISPLAY 0.638298 (2309 4000);
PAINT MONO (2309 4000);
FORCEPROP 2 LAST $XR0 181 
J 0
(2189 4000);
DISPLAY 0.638298 (2189 4000);
PAINT MONO (2189 4000);
FORCEPROP 2 LAST PATH I119
J 0
(2325 4050);
DISPLAY 1.021277 (2325 4050);
PAINT ORANGE (2325 4050);
DISPLAY INVISIBLE (2325 4050);
FORCEPROP 2 LAST CDS_LIB mstr_standard
J 0
(2000 4000);
PAINT ORANGE (2000 4000);
DISPLAY INVISIBLE (2000 4000);
FORCEPROP 1 LAST OFFPAGE TRUE
J 0
(2325 3875);
DISPLAY 0.872340 (2325 3875);
PAINT GREEN (2325 3875);
DISPLAY INVISIBLE (2325 3875);
FORCEPROP 1 LAST COMMENT_BODY TRUE
J 0
(1955 3905);
DISPLAY 0.872340 (1955 3905);
PAINT GREEN (1955 3905);
DISPLAY INVISIBLE (1955 3905);
FORCEADD OFFPAGE..1
(-2900 2700);
FORCEPROP 2 LAST $XR0 161 
J 0
(-3152 2700);
DISPLAY 0.638298 (-3152 2700);
PAINT MONO (-3152 2700);
FORCEPROP 2 LAST PATH I12
J 0
(-3150 2750);
DISPLAY 1.021277 (-3150 2750);
PAINT ORANGE (-3150 2750);
DISPLAY INVISIBLE (-3150 2750);
FORCEPROP 2 LAST CDS_LIB mstr_standard
J 0
(-2900 2700);
PAINT ORANGE (-2900 2700);
DISPLAY INVISIBLE (-2900 2700);
FORCEPROP 1 LAST OFFPAGE TRUE
J 0
(-2575 2575);
DISPLAY 0.872340 (-2575 2575);
PAINT GREEN (-2575 2575);
DISPLAY INVISIBLE (-2575 2575);
FORCEPROP 1 LAST COMMENT_BODY TRUE
J 0
(-2775 2600);
DISPLAY 0.872340 (-2775 2600);
PAINT GREEN (-2775 2600);
DISPLAY INVISIBLE (-2775 2600);
FORCEADD OFFPAGE..1
R 2
(2000 4100);
FORCEPROP 2 LAST $XR0 191 
J 0
(2186 4100);
DISPLAY 0.638298 (2186 4100);
PAINT MONO (2186 4100);
FORCEPROP 2 LAST PATH I120
J 0
(2200 4150);
DISPLAY 1.021277 (2200 4150);
PAINT ORANGE (2200 4150);
DISPLAY INVISIBLE (2200 4150);
FORCEPROP 2 LAST CDS_LIB mstr_standard
J 2
(2000 4100);
PAINT ORANGE (2000 4100);
DISPLAY INVISIBLE (2000 4100);
FORCEPROP 1 LAST OFFPAGE TRUE
J 2
(1675 3975);
DISPLAY 0.872340 (1675 3975);
PAINT GREEN (1675 3975);
DISPLAY INVISIBLE (1675 3975);
FORCEPROP 1 LAST COMMENT_BODY TRUE
J 2
(1875 4000);
DISPLAY 0.872340 (1875 4000);
PAINT GREEN (1875 4000);
DISPLAY INVISIBLE (1875 4000);
FORCEADD OFFPAGE..2
(2000 4150);
FORCEPROP 2 LAST $XR2 164 
J 0
(2429 4150);
DISPLAY 0.638298 (2429 4150);
PAINT MONO (2429 4150);
FORCEPROP 2 LAST $XR1 119 
J 0
(2309 4150);
DISPLAY 0.638298 (2309 4150);
PAINT MONO (2309 4150);
FORCEPROP 2 LAST $XR0 181 
J 0
(2189 4150);
DISPLAY 0.638298 (2189 4150);
PAINT MONO (2189 4150);
FORCEPROP 2 LAST PATH I121
J 0
(2450 4200);
DISPLAY 1.021277 (2450 4200);
PAINT ORANGE (2450 4200);
DISPLAY INVISIBLE (2450 4200);
FORCEPROP 2 LAST CDS_LIB mstr_standard
J 0
(2000 4150);
PAINT MONO (2000 4150);
DISPLAY INVISIBLE (2000 4150);
FORCEPROP 1 LAST OFFPAGE TRUE
J 0
(2325 4025);
DISPLAY 0.872340 (2325 4025);
PAINT GREEN (2325 4025);
DISPLAY INVISIBLE (2325 4025);
FORCEPROP 1 LAST COMMENT_BODY TRUE
J 0
(1955 4055);
DISPLAY 0.872340 (1955 4055);
PAINT GREEN (1955 4055);
DISPLAY INVISIBLE (1955 4055);
FORCEADD OFFPAGE..2
(2000 4200);
FORCEPROP 2 LAST $XR2 164 
J 0
(2429 4200);
DISPLAY 0.638298 (2429 4200);
PAINT MONO (2429 4200);
FORCEPROP 2 LAST $XR1 119 
J 0
(2309 4200);
DISPLAY 0.638298 (2309 4200);
PAINT MONO (2309 4200);
FORCEPROP 2 LAST $XR0 181 
J 0
(2189 4200);
DISPLAY 0.638298 (2189 4200);
PAINT MONO (2189 4200);
FORCEPROP 2 LAST PATH I122
J 0
(2450 4250);
DISPLAY 1.021277 (2450 4250);
PAINT ORANGE (2450 4250);
DISPLAY INVISIBLE (2450 4250);
FORCEPROP 2 LAST CDS_LIB mstr_standard
J 0
(2000 4200);
PAINT MONO (2000 4200);
DISPLAY INVISIBLE (2000 4200);
FORCEPROP 1 LAST OFFPAGE TRUE
J 0
(2325 4075);
DISPLAY 0.872340 (2325 4075);
PAINT GREEN (2325 4075);
DISPLAY INVISIBLE (2325 4075);
FORCEPROP 1 LAST COMMENT_BODY TRUE
J 0
(1955 4105);
DISPLAY 0.872340 (1955 4105);
PAINT GREEN (1955 4105);
DISPLAY INVISIBLE (1955 4105);
FORCEADD OFFPAGE..2
(2000 4250);
FORCEPROP 2 LAST $XR2 164 
J 0
(2429 4250);
DISPLAY 0.638298 (2429 4250);
PAINT MONO (2429 4250);
FORCEPROP 2 LAST $XR1 119 
J 0
(2309 4250);
DISPLAY 0.638298 (2309 4250);
PAINT MONO (2309 4250);
FORCEPROP 2 LAST $XR0 181 
J 0
(2189 4250);
DISPLAY 0.638298 (2189 4250);
PAINT MONO (2189 4250);
FORCEPROP 2 LAST PATH I123
J 0
(2450 4300);
DISPLAY 1.021277 (2450 4300);
PAINT ORANGE (2450 4300);
DISPLAY INVISIBLE (2450 4300);
FORCEPROP 2 LAST CDS_LIB mstr_standard
J 0
(2000 4250);
PAINT MONO (2000 4250);
DISPLAY INVISIBLE (2000 4250);
FORCEPROP 1 LAST OFFPAGE TRUE
J 0
(2325 4125);
DISPLAY 0.872340 (2325 4125);
PAINT GREEN (2325 4125);
DISPLAY INVISIBLE (2325 4125);
FORCEPROP 1 LAST COMMENT_BODY TRUE
J 0
(1955 4155);
DISPLAY 0.872340 (1955 4155);
PAINT GREEN (1955 4155);
DISPLAY INVISIBLE (1955 4155);
FORCEADD OFFPAGE..2
(2000 4300);
FORCEPROP 2 LAST $XR0 141 
J 0
(2189 4300);
DISPLAY 0.638298 (2189 4300);
PAINT MONO (2189 4300);
FORCEPROP 2 LAST PATH I124
J 0
(2200 4350);
DISPLAY 1.021277 (2200 4350);
PAINT ORANGE (2200 4350);
DISPLAY INVISIBLE (2200 4350);
FORCEPROP 2 LAST CDS_LIB mstr_standard
J 0
(2000 4300);
PAINT ORANGE (2000 4300);
DISPLAY INVISIBLE (2000 4300);
FORCEPROP 1 LAST OFFPAGE TRUE
J 0
(2325 4175);
DISPLAY 0.872340 (2325 4175);
PAINT GREEN (2325 4175);
DISPLAY INVISIBLE (2325 4175);
FORCEPROP 1 LAST COMMENT_BODY TRUE
J 0
(1955 4205);
DISPLAY 0.872340 (1955 4205);
PAINT GREEN (1955 4205);
DISPLAY INVISIBLE (1955 4205);
FORCEADD OFFPAGE..2
(2000 4350);
FORCEPROP 2 LAST $XR0 141 
J 0
(2189 4350);
DISPLAY 0.638298 (2189 4350);
PAINT MONO (2189 4350);
FORCEPROP 2 LAST PATH I125
J 0
(2200 4400);
DISPLAY 1.021277 (2200 4400);
PAINT ORANGE (2200 4400);
DISPLAY INVISIBLE (2200 4400);
FORCEPROP 2 LAST CDS_LIB mstr_standard
J 2
(2000 4350);
PAINT ORANGE (2000 4350);
DISPLAY INVISIBLE (2000 4350);
FORCEPROP 1 LAST OFFPAGE TRUE
J 0
(2325 4225);
DISPLAY 0.872340 (2325 4225);
PAINT GREEN (2325 4225);
DISPLAY INVISIBLE (2325 4225);
FORCEPROP 1 LAST COMMENT_BODY TRUE
J 0
(1955 4255);
DISPLAY 0.872340 (1955 4255);
PAINT GREEN (1955 4255);
DISPLAY INVISIBLE (1955 4255);
FORCEADD OFFPAGE..3
(2350 3900);
FORCEPROP 2 LAST $XR4 199 
J 0
(2684 3864);
DISPLAY 0.638298 (2684 3864);
PAINT MONO (2684 3864);
FORCEPROP 2 LAST $XR3 181 
J 0
(2564 3864);
DISPLAY 0.638298 (2564 3864);
PAINT MONO (2564 3864);
FORCEPROP 2 LAST $XR2 247 
J 0
(2804 3900);
DISPLAY 0.638298 (2804 3900);
PAINT MONO (2804 3900);
FORCEPROP 2 LAST $XR1 159 
J 0
(2684 3900);
DISPLAY 0.638298 (2684 3900);
PAINT MONO (2684 3900);
FORCEPROP 2 LAST $XR0 138 
J 0
(2564 3900);
DISPLAY 0.638298 (2564 3900);
PAINT MONO (2564 3900);
FORCEPROP 2 LAST PATH I126
J 0
(2825 3950);
DISPLAY 1.021277 (2825 3950);
PAINT ORANGE (2825 3950);
DISPLAY INVISIBLE (2825 3950);
FORCEPROP 2 LAST CDS_LIB mstr_standard
J 0
(2350 3900);
PAINT ORANGE (2350 3900);
DISPLAY INVISIBLE (2350 3900);
FORCEPROP 1 LAST OFFPAGE TRUE
J 0
(2675 3775);
DISPLAY 0.872340 (2675 3775);
PAINT GREEN (2675 3775);
DISPLAY INVISIBLE (2675 3775);
FORCEPROP 1 LAST COMMENT_BODY TRUE
J 0
(2300 3800);
DISPLAY 0.872340 (2300 3800);
PAINT GREEN (2300 3800);
DISPLAY INVISIBLE (2300 3800);
FORCEADD OFFPAGE..1
R 2
(2000 4450);
FORCEPROP 2 LAST $XR0 141 
J 0
(2186 4450);
DISPLAY 0.638298 (2186 4450);
PAINT MONO (2186 4450);
FORCEPROP 2 LAST PATH I127
J 0
(2200 4500);
DISPLAY 1.021277 (2200 4500);
PAINT ORANGE (2200 4500);
DISPLAY INVISIBLE (2200 4500);
FORCEPROP 2 LAST CDS_LIB mstr_standard
J 0
(2000 4450);
PAINT ORANGE (2000 4450);
DISPLAY INVISIBLE (2000 4450);
FORCEPROP 1 LAST OFFPAGE TRUE
J 2
(1675 4325);
DISPLAY 0.872340 (1675 4325);
PAINT GREEN (1675 4325);
DISPLAY INVISIBLE (1675 4325);
FORCEPROP 1 LAST COMMENT_BODY TRUE
J 2
(1875 4350);
DISPLAY 0.872340 (1875 4350);
PAINT GREEN (1875 4350);
DISPLAY INVISIBLE (1875 4350);
FORCEADD OFFPAGE..1
R 2
(2000 4500);
FORCEPROP 2 LAST $XR0 141 
J 0
(2186 4500);
DISPLAY 0.638298 (2186 4500);
PAINT MONO (2186 4500);
FORCEPROP 2 LAST PATH I128
J 0
(2200 4550);
DISPLAY 1.021277 (2200 4550);
PAINT ORANGE (2200 4550);
DISPLAY INVISIBLE (2200 4550);
FORCEPROP 2 LAST CDS_LIB mstr_standard
J 0
(2000 4500);
PAINT ORANGE (2000 4500);
DISPLAY INVISIBLE (2000 4500);
FORCEPROP 1 LAST OFFPAGE TRUE
J 2
(1675 4375);
DISPLAY 0.872340 (1675 4375);
PAINT GREEN (1675 4375);
DISPLAY INVISIBLE (1675 4375);
FORCEPROP 1 LAST COMMENT_BODY TRUE
J 2
(1875 4400);
DISPLAY 0.872340 (1875 4400);
PAINT GREEN (1875 4400);
DISPLAY INVISIBLE (1875 4400);
FORCEADD OFFPAGE..1
R 2
(4050 4475);
FORCEPROP 2 LAST $XR0 66 
J 0
(4236 4475);
DISPLAY 0.638298 (4236 4475);
PAINT MONO (4236 4475);
FORCEPROP 2 LAST CDS_LIB mstr_standard
J 0
(4050 4475);
PAINT ORANGE (4050 4475);
DISPLAY INVISIBLE (4050 4475);
FORCEPROP 2 LAST PATH I129
J 0
(4250 4525);
DISPLAY 1.021277 (4250 4525);
PAINT ORANGE (4250 4525);
DISPLAY INVISIBLE (4250 4525);
FORCEPROP 1 LAST OFFPAGE TRUE
J 2
(3725 4350);
DISPLAY 0.872340 (3725 4350);
PAINT GREEN (3725 4350);
DISPLAY INVISIBLE (3725 4350);
FORCEPROP 1 LAST COMMENT_BODY TRUE
J 2
(3925 4375);
DISPLAY 0.872340 (3925 4375);
PAINT GREEN (3925 4375);
DISPLAY INVISIBLE (3925 4375);
FORCEADD OFFPAGE..5
(-2925 2850);
FORCEPROP 2 LAST $XR0 147 
J 0
(-3180 2850);
DISPLAY 0.638298 (-3180 2850);
PAINT MONO (-3180 2850);
FORCEPROP 2 LAST PATH I13
J 0
(-3175 2900);
DISPLAY 1.021277 (-3175 2900);
PAINT ORANGE (-3175 2900);
DISPLAY INVISIBLE (-3175 2900);
FORCEPROP 2 LAST CDS_LIB mstr_standard
J 0
(-2925 2850);
PAINT ORANGE (-2925 2850);
DISPLAY INVISIBLE (-2925 2850);
FORCEPROP 1 LAST OFFPAGE TRUE
J 0
(-2600 2725);
DISPLAY 0.872340 (-2600 2725);
PAINT GREEN (-2600 2725);
DISPLAY INVISIBLE (-2600 2725);
FORCEPROP 1 LAST COMMENT_BODY TRUE
J 0
(-2825 2775);
DISPLAY 0.872340 (-2825 2775);
PAINT GREEN (-2825 2775);
DISPLAY INVISIBLE (-2825 2775);
FORCEADD OFFPAGE..1
R 2
(4050 4575);
FORCEPROP 2 LAST $XR0 66 
J 0
(4236 4575);
DISPLAY 0.638298 (4236 4575);
PAINT MONO (4236 4575);
FORCEPROP 2 LAST CDS_LIB mstr_standard
J 0
(4050 4575);
PAINT ORANGE (4050 4575);
DISPLAY INVISIBLE (4050 4575);
FORCEPROP 2 LAST PATH I130
J 0
(4250 4625);
DISPLAY 1.021277 (4250 4625);
PAINT ORANGE (4250 4625);
DISPLAY INVISIBLE (4250 4625);
FORCEPROP 1 LAST OFFPAGE TRUE
J 2
(3725 4450);
DISPLAY 0.872340 (3725 4450);
PAINT GREEN (3725 4450);
DISPLAY INVISIBLE (3725 4450);
FORCEPROP 1 LAST COMMENT_BODY TRUE
J 2
(3925 4475);
DISPLAY 0.872340 (3925 4475);
PAINT GREEN (3925 4475);
DISPLAY INVISIBLE (3925 4475);
FORCEADD OFFPAGE..5
(-2875 4700);
FORCEPROP 2 LAST $XR0 66 
J 0
(-3129 4700);
DISPLAY 0.638298 (-3129 4700);
PAINT MONO (-3129 4700);
FORCEPROP 2 LAST PATH I131
J 0
(-3125 4750);
DISPLAY 1.021277 (-3125 4750);
PAINT ORANGE (-3125 4750);
DISPLAY INVISIBLE (-3125 4750);
FORCEPROP 2 LAST CDS_LIB mstr_standard
J 0
(-2875 4700);
PAINT ORANGE (-2875 4700);
DISPLAY INVISIBLE (-2875 4700);
FORCEPROP 1 LAST OFFPAGE TRUE
J 0
(-2550 4575);
DISPLAY 0.872340 (-2550 4575);
PAINT GREEN (-2550 4575);
DISPLAY INVISIBLE (-2550 4575);
FORCEPROP 1 LAST COMMENT_BODY TRUE
J 0
(-2775 4625);
DISPLAY 0.872340 (-2775 4625);
PAINT GREEN (-2775 4625);
DISPLAY INVISIBLE (-2775 4625);
FORCEADD TAP..1
R 2
(-1250 3800);
FORCEPROP 3 LASTPIN (-1200 3800) SIG_NAME P3E_CPU1_PE3_MP_RXN<4>
J 0
(-1190 3810);
DISPLAY 0.659574 (-1190 3810);
PAINT MONO (-1190 3810);
DISPLAY INVISIBLE (-1190 3810);
FORCEPROP 1 LASTPIN (-1200 3800) BN 4
J 2
(-1188 3808);
DISPLAY 0.617021 (-1188 3808);
PAINT GREEN (-1188 3808);
FORCEPROP 1 LAST PATH I132
J 2
(-1248 3800);
DISPLAY 0.872340 (-1248 3800);
PAINT GREEN (-1248 3800);
DISPLAY INVISIBLE (-1248 3800);
FORCEPROP 2 LAST CDS_LIB mstr_standard
J 0
(-1250 3800);
PAINT MONO (-1250 3800);
DISPLAY INVISIBLE (-1250 3800);
FORCEPROP 1 LAST BODY_TYPE PLUMBING
J 2
(-1250 3850);
DISPLAY 1.446809 (-1250 3850);
PAINT GREEN (-1250 3850);
DISPLAY INVISIBLE (-1250 3850);
FORCEPROP 1 LAST HDL_TAP TRUE
J 2
(-1575 3675);
DISPLAY 1.446809 (-1575 3675);
PAINT GREEN (-1575 3675);
DISPLAY INVISIBLE (-1575 3675);
FORCEADD DM-FCI-CONN76-8R-GP-U-01..1
(100 3475);
FORCEPROP 2 LASTPIN (725 3650) $PN H6
J 0
(735 3660);
DISPLAY 0.808511 (735 3660);
PAINT ORANGE (735 3660);
FORCEPROP 2 LASTPIN (725 3700) $PN G6
J 0
(735 3710);
DISPLAY 0.808511 (735 3710);
PAINT ORANGE (735 3710);
FORCEPROP 2 LASTPIN (725 4200) $PN G5
J 0
(735 4210);
DISPLAY 0.808511 (735 4210);
PAINT ORANGE (735 4210);
FORCEPROP 2 LASTPIN (725 4150) $PN H5
J 0
(735 4160);
DISPLAY 0.808511 (735 4160);
PAINT ORANGE (735 4160);
FORCEPROP 2 LASTPIN (725 4100) $PN I5
J 0
(735 4110);
DISPLAY 0.808511 (735 4110);
PAINT ORANGE (735 4110);
FORCEPROP 2 LASTPIN (-525 2550) $PN I4
J 2
(-535 2560);
DISPLAY 0.808511 (-535 2560);
PAINT ORANGE (-535 2560);
FORCEPROP 2 LASTPIN (-525 2500) $PN J4
J 2
(-535 2510);
DISPLAY 0.808511 (-535 2510);
PAINT ORANGE (-535 2510);
FORCEPROP 2 LASTPIN (-525 2600) $PN H4
J 2
(-535 2610);
DISPLAY 0.808511 (-535 2610);
PAINT ORANGE (-535 2610);
FORCEPROP 2 LASTPIN (-525 2650) $PN G4
J 2
(-535 2660);
DISPLAY 0.808511 (-535 2660);
PAINT ORANGE (-535 2660);
FORCEPROP 2 LASTPIN (-525 2700) $PN F4
J 2
(-535 2710);
DISPLAY 0.808511 (-535 2710);
PAINT ORANGE (-535 2710);
FORCEPROP 2 LASTPIN (-525 2850) $PN C4
J 2
(-535 2860);
DISPLAY 0.808511 (-535 2860);
PAINT ORANGE (-535 2860);
FORCEPROP 2 LASTPIN (-525 2750) $PN E4
J 2
(-535 2760);
DISPLAY 0.808511 (-535 2760);
PAINT ORANGE (-535 2760);
FORCEPROP 2 LASTPIN (-525 2800) $PN D4
J 2
(-535 2810);
DISPLAY 0.808511 (-535 2810);
PAINT ORANGE (-535 2810);
FORCEPROP 2 LASTPIN (-525 2900) $PN B4
J 2
(-535 2910);
DISPLAY 0.808511 (-535 2910);
PAINT ORANGE (-535 2910);
FORCEPROP 2 LASTPIN (-525 3100) $PN H3
J 2
(-535 3110);
DISPLAY 0.808511 (-535 3110);
PAINT ORANGE (-535 3110);
FORCEPROP 2 LASTPIN (-525 3200) $PN F3
J 2
(-535 3210);
DISPLAY 0.808511 (-535 3210);
PAINT ORANGE (-535 3210);
FORCEPROP 2 LASTPIN (-525 3150) $PN G3
J 2
(-535 3160);
DISPLAY 0.808511 (-535 3160);
PAINT ORANGE (-535 3160);
FORCEPROP 2 LASTPIN (-525 3250) $PN E3
J 2
(-535 3260);
DISPLAY 0.808511 (-535 3260);
PAINT ORANGE (-535 3260);
FORCEPROP 2 LASTPIN (-525 3300) $PN D3
J 2
(-535 3310);
DISPLAY 0.808511 (-535 3310);
PAINT ORANGE (-535 3310);
FORCEPROP 2 LASTPIN (-525 3400) $PN B3
J 2
(-535 3410);
DISPLAY 0.808511 (-535 3410);
PAINT ORANGE (-535 3410);
FORCEPROP 2 LASTPIN (-525 3450) $PN A3
J 2
(-535 3460);
DISPLAY 0.808511 (-535 3460);
PAINT ORANGE (-535 3460);
FORCEPROP 2 LASTPIN (-525 3600) $PN I2
J 2
(-535 3610);
DISPLAY 0.808511 (-535 3610);
PAINT ORANGE (-535 3610);
FORCEPROP 2 LASTPIN (-525 3750) $PN F2
J 2
(-535 3760);
DISPLAY 0.808511 (-535 3760);
PAINT ORANGE (-535 3760);
FORCEPROP 2 LASTPIN (-525 3650) $PN H2
J 2
(-535 3660);
DISPLAY 0.808511 (-535 3660);
PAINT ORANGE (-535 3660);
FORCEPROP 2 LASTPIN (-525 3700) $PN G2
J 2
(-535 3710);
DISPLAY 0.808511 (-535 3710);
PAINT ORANGE (-535 3710);
FORCEPROP 2 LASTPIN (-525 3850) $PN D2
J 2
(-535 3860);
DISPLAY 0.808511 (-535 3860);
PAINT ORANGE (-535 3860);
FORCEPROP 2 LASTPIN (-525 3800) $PN E2
J 2
(-535 3810);
DISPLAY 0.808511 (-535 3810);
PAINT ORANGE (-535 3810);
FORCEPROP 2 LASTPIN (-525 3900) $PN C2
J 2
(-535 3910);
DISPLAY 0.808511 (-535 3910);
PAINT ORANGE (-535 3910);
FORCEPROP 2 LASTPIN (-525 3950) $PN B2
J 2
(-535 3960);
DISPLAY 0.808511 (-535 3960);
PAINT ORANGE (-535 3960);
FORCEPROP 2 LASTPIN (-525 4100) $PN I1
J 2
(-535 4110);
DISPLAY 0.808511 (-535 4110);
PAINT ORANGE (-535 4110);
FORCEPROP 2 LASTPIN (-525 4350) $PN D1
J 2
(-535 4360);
DISPLAY 0.808511 (-535 4360);
PAINT ORANGE (-535 4360);
FORCEPROP 2 LASTPIN (-525 4300) $PN E1
J 2
(-535 4310);
DISPLAY 0.808511 (-535 4310);
PAINT ORANGE (-535 4310);
FORCEPROP 2 LASTPIN (-525 4400) $PN C1
J 2
(-535 4410);
DISPLAY 0.808511 (-535 4410);
PAINT ORANGE (-535 4410);
FORCEPROP 2 LASTPIN (-525 4450) $PN B1
J 2
(-535 4460);
DISPLAY 0.808511 (-535 4460);
PAINT ORANGE (-535 4460);
FORCEPROP 2 LASTPIN (-525 4500) $PN A1
J 2
(-535 4510);
DISPLAY 0.808511 (-535 4510);
PAINT ORANGE (-535 4510);
FORCEPROP 2 LASTPIN (725 2500) $PN J8
J 0
(735 2510);
DISPLAY 0.808511 (735 2510);
PAINT ORANGE (735 2510);
FORCEPROP 2 LASTPIN (725 2650) $PN G8
J 0
(735 2660);
DISPLAY 0.808511 (735 2660);
PAINT ORANGE (735 2660);
FORCEPROP 2 LASTPIN (725 2700) $PN F8
J 0
(735 2710);
DISPLAY 0.808511 (735 2710);
PAINT ORANGE (735 2710);
FORCEPROP 2 LASTPIN (725 2750) $PN E8
J 0
(735 2760);
DISPLAY 0.808511 (735 2760);
PAINT ORANGE (735 2760);
FORCEPROP 2 LASTPIN (725 3250) $PN E7
J 0
(735 3260);
DISPLAY 0.808511 (735 3260);
PAINT ORANGE (735 3260);
FORCEPROP 2 LASTPIN (725 3350) $PN C7
J 0
(735 3360);
DISPLAY 0.808511 (735 3360);
PAINT ORANGE (735 3360);
FORCEPROP 2 LASTPIN (725 3400) $PN B7
J 0
(735 3410);
DISPLAY 0.808511 (735 3410);
PAINT ORANGE (735 3410);
FORCEPROP 2 LASTPIN (725 3550) $PN J6
J 0
(735 3560);
DISPLAY 0.808511 (735 3560);
PAINT ORANGE (735 3560);
FORCEPROP 2 LASTPIN (725 4250) $PN F5
J 0
(735 4260);
DISPLAY 0.808511 (735 4260);
PAINT ORANGE (735 4260);
FORCEPROP 2 LASTPIN (725 3600) $PN I6
J 0
(735 3610);
DISPLAY 0.808511 (735 3610);
PAINT ORANGE (735 3610);
FORCEPROP 2 LASTPIN (725 3750) $PN F6
J 0
(735 3760);
DISPLAY 0.808511 (735 3760);
PAINT ORANGE (735 3760);
FORCEPROP 2 LASTPIN (725 3800) $PN E6
J 0
(735 3810);
DISPLAY 0.808511 (735 3810);
PAINT ORANGE (735 3810);
FORCEPROP 2 LASTPIN (725 3850) $PN D6
J 0
(735 3860);
DISPLAY 0.808511 (735 3860);
PAINT ORANGE (735 3860);
FORCEPROP 2 LASTPIN (725 3900) $PN C6
J 0
(735 3910);
DISPLAY 0.808511 (735 3910);
PAINT ORANGE (735 3910);
FORCEPROP 2 LASTPIN (725 3950) $PN B6
J 0
(735 3960);
DISPLAY 0.808511 (735 3960);
PAINT ORANGE (735 3960);
FORCEPROP 2 LASTPIN (725 4300) $PN E5
J 0
(735 4310);
DISPLAY 0.808511 (735 4310);
PAINT ORANGE (735 4310);
FORCEPROP 2 LASTPIN (725 4400) $PN C5
J 0
(735 4410);
DISPLAY 0.808511 (735 4410);
PAINT ORANGE (735 4410);
FORCEPROP 2 LASTPIN (725 4450) $PN B5
J 0
(735 4460);
DISPLAY 0.808511 (735 4460);
PAINT ORANGE (735 4460);
FORCEPROP 2 LASTPIN (725 3300) $PN D7
J 0
(735 3310);
DISPLAY 0.808511 (735 3310);
PAINT ORANGE (735 3310);
FORCEPROP 2 LASTPIN (725 3200) $PN F7
J 0
(735 3210);
DISPLAY 0.808511 (735 3210);
PAINT ORANGE (735 3210);
FORCEPROP 2 LASTPIN (725 3150) $PN G7
J 0
(735 3160);
DISPLAY 0.808511 (735 3160);
PAINT ORANGE (735 3160);
FORCEPROP 2 LASTPIN (725 3100) $PN H7
J 0
(735 3110);
DISPLAY 0.808511 (735 3110);
PAINT ORANGE (735 3110);
FORCEPROP 2 LASTPIN (725 3050) $PN I7
J 0
(735 3060);
DISPLAY 0.808511 (735 3060);
PAINT ORANGE (735 3060);
FORCEPROP 2 LASTPIN (725 2950) $PN A8
J 0
(735 2960);
DISPLAY 0.808511 (735 2960);
PAINT ORANGE (735 2960);
FORCEPROP 2 LASTPIN (725 2900) $PN B8
J 0
(735 2910);
DISPLAY 0.808511 (735 2910);
PAINT ORANGE (735 2910);
FORCEPROP 2 LASTPIN (725 2850) $PN C8
J 0
(735 2860);
DISPLAY 0.808511 (735 2860);
PAINT ORANGE (735 2860);
FORCEPROP 2 LASTPIN (725 2800) $PN D8
J 0
(735 2810);
DISPLAY 0.808511 (735 2810);
PAINT ORANGE (735 2810);
FORCEPROP 2 LASTPIN (725 2600) $PN H8
J 0
(735 2610);
DISPLAY 0.808511 (735 2610);
PAINT ORANGE (735 2610);
FORCEPROP 1 LAST LOCATION J1F1
J 0
(-375 4725);
DISPLAY 0.617021 (-375 4725);
PAINT GREEN (-375 4725);
FORCEPROP 2 LASTPIN (725 3450) $PN A7
J 0
(735 3460);
DISPLAY 0.808511 (735 3460);
PAINT ORANGE (735 3460);
FORCEPROP 2 LASTPIN (-525 4250) $PN F1
J 2
(-535 4260);
DISPLAY 0.808511 (-535 4260);
PAINT ORANGE (-535 4260);
FORCEPROP 2 LASTPIN (-525 4200) $PN G1
J 2
(-535 4210);
DISPLAY 0.808511 (-535 4210);
PAINT ORANGE (-535 4210);
FORCEPROP 2 LASTPIN (-525 4150) $PN H1
J 2
(-535 4160);
DISPLAY 0.808511 (-535 4160);
PAINT ORANGE (-535 4160);
FORCEPROP 2 LASTPIN (-525 4000) $PN A2
J 2
(-535 4010);
DISPLAY 0.808511 (-535 4010);
PAINT ORANGE (-535 4010);
FORCEPROP 2 LASTPIN (-525 3550) $PN J2
J 2
(-535 3560);
DISPLAY 0.808511 (-535 3560);
PAINT ORANGE (-535 3560);
FORCEPROP 2 LASTPIN (-525 3350) $PN C3
J 2
(-535 3360);
DISPLAY 0.808511 (-535 3360);
PAINT ORANGE (-535 3360);
FORCEPROP 2 LASTPIN (725 4000) $PN A6
J 0
(735 4010);
DISPLAY 0.808511 (735 4010);
PAINT ORANGE (735 4010);
FORCEPROP 2 LASTPIN (725 4350) $PN D5
J 0
(735 4360);
DISPLAY 0.808511 (735 4360);
PAINT ORANGE (735 4360);
FORCEPROP 2 LASTPIN (-525 3050) $PN I3
J 2
(-535 3060);
DISPLAY 0.808511 (-535 3060);
PAINT ORANGE (-535 3060);
FORCEPROP 2 LASTPIN (-525 2950) $PN A4
J 2
(-535 2960);
DISPLAY 0.808511 (-535 2960);
PAINT ORANGE (-535 2960);
FORCEPROP 2 LASTPIN (725 4500) $PN A5
J 0
(735 4510);
DISPLAY 0.808511 (735 4510);
PAINT ORANGE (735 4510);
FORCEPROP 0 LAST NEW_PN 20.82092.076
J 0
(-450 4900);
DISPLAY 1.021277 (-450 4900);
PAINT BROWN (-450 4900);
DISPLAY BOTH (-450 4900);
FORCEPROP 0 LAST CONFIG H22707-001
J 0
(-450 4950);
DISPLAY 1.021277 (-450 4950);
PAINT BROWN (-450 4950);
DISPLAY BOTH (-450 4950);
FORCEPROP 1 LAST VALUE DM-FCI-CONN76-8R-GP-U-01
J 0
(-350 2200);
DISPLAY 0.617021 (-350 2200);
PAINT GREEN (-350 2200);
FORCEPROP 2 LASTPIN (725 2550) $PN I8
J 0
(735 2560);
DISPLAY 0.808511 (735 2560);
PAINT ORANGE (735 2560);
FORCEPROP 1 LAST PACK_TYPE CONN-G4
J 0
(100 3475);
DISPLAY 0.617021 (100 3475);
PAINT GREEN (100 3475);
DISPLAY INVISIBLE (100 3475);
FORCEPROP 2 LAST SEC 1
J 0
(-375 4775);
DISPLAY 0.680851 (-375 4775);
PAINT MONO (-375 4775);
DISPLAY INVISIBLE (-375 4775);
FORCEPROP 2 LAST SEC_TYPE CONN-G4
J 0
(-375 4775);
DISPLAY 1.021277 (-375 4775);
PAINT ORANGE (-375 4775);
DISPLAY INVISIBLE (-375 4775);
FORCEPROP 1 LAST PART_NUMBER ZZ.82092.07601
J 0
(100 3435);
DISPLAY 0.617021 (100 3435);
PAINT GREEN (100 3435);
DISPLAY INVISIBLE (100 3435);
FORCEPROP 2 LAST CDS_LIB w_hdl
J 0
(100 3475);
PAINT MONO (100 3475);
DISPLAY INVISIBLE (100 3475);
FORCEPROP 1 LAST PATH I134
J 0
(100 3515);
DISPLAY 0.617021 (100 3515);
PAINT GREEN (100 3515);
DISPLAY INVISIBLE (100 3515);
FORCEPROP 1 LAST CDS_LMAN_SYM_OUTLINE -475,1225,475,-1225
J 0
(100 3475);
DISPLAY 0.468085 (100 3475);
PAINT GREEN (100 3475);
DISPLAY INVISIBLE (100 3475);
FORCEADD GND..1
(-2200 1125);
FORCEPROP 3 LASTPIN (-2200 1175) SIG_NAME GND\g
J 0
(-2190 1185);
DISPLAY 0.659574 (-2190 1185);
PAINT MONO (-2190 1185);
DISPLAY INVISIBLE (-2190 1185);
FORCEPROP 1 LAST HDL_POWER GND
J 0
(-2200 1275);
DISPLAY 0.872340 (-2200 1275);
PAINT GREEN (-2200 1275);
DISPLAY INVISIBLE (-2200 1275);
FORCEPROP 1 LAST BODY_TYPE PLUMBING
J 0
(-2245 1082);
DISPLAY 0.340426 (-2245 1082);
PAINT GREEN (-2245 1082);
DISPLAY INVISIBLE (-2245 1082);
FORCEPROP 1 LAST SIZE 1B
J 0
(-2125 1075);
DISPLAY 0.872340 (-2125 1075);
PAINT AQUA (-2125 1075);
DISPLAY INVISIBLE (-2125 1075);
FORCEPROP 1 LAST VOLTAGE 0.0V
J 0
(-2245 1082);
DISPLAY 0.340426 (-2245 1082);
PAINT SKYBLUE (-2245 1082);
DISPLAY INVISIBLE (-2245 1082);
FORCEPROP 1 LAST PATH I136
J 0
(-2125 1125);
DISPLAY 0.872340 (-2125 1125);
PAINT AQUA (-2125 1125);
DISPLAY INVISIBLE (-2125 1125);
FORCEPROP 2 LAST CDS_LIB mstr_symbols
J 0
(-2200 1125);
DISPLAY INVISIBLE (-2200 1125);
FORCEADD RES..1
R 3
(-2200 1300);
FORCEPROP 1 LAST PART_NUMBER G21497-005
J 0
(-2150 1175);
DISPLAY 0.617021 (-2150 1175);
PAINT BLUE (-2150 1175);
FORCEPROP 1 LAST PACK_TYPE 0402
J 0
(-2150 1125);
DISPLAY 0.617021 (-2150 1125);
PAINT SKYBLUE (-2150 1125);
FORCEPROP 1 LASTPIN (-2200 1200) $PN 2
J 2
(-2212 1188);
DISPLAY 0.617021 (-2212 1188);
PAINT MONO (-2212 1188);
FORCEPROP 1 LAST LOCATION R9T8
J 0
(-2150 1425);
DISPLAY 0.617021 (-2150 1425);
PAINT AQUA (-2150 1425);
FORCEPROP 1 LAST TOLERANCE 5%
J 0
(-2150 1325);
DISPLAY 0.617021 (-2150 1325);
PAINT SKYBLUE (-2150 1325);
FORCEPROP 1 LAST VALUE 0.0
J 0
(-2150 1375);
DISPLAY 0.617021 (-2150 1375);
PAINT SKYBLUE (-2150 1375);
FORCEPROP 1 LASTPIN (-2200 1400) $PN 1
J 2
(-2212 1388);
DISPLAY 0.617021 (-2212 1388);
PAINT MONO (-2212 1388);
FORCEPROP 1 LAST MATERIAL CHIP
J 0
(-2150 1225);
DISPLAY 0.617021 (-2150 1225);
PAINT SKYBLUE (-2150 1225);
FORCEPROP 1 LAST WATTAGE 1/16W
J 0
(-2150 1275);
DISPLAY 0.617021 (-2150 1275);
PAINT SKYBLUE (-2150 1275);
FORCEPROP 1 LAST PATH I137
R 1
J 0
(-2350 1350);
DISPLAY 0.978723 (-2350 1350);
PAINT WHITE (-2350 1350);
DISPLAY INVISIBLE (-2350 1350);
FORCEPROP 2 LAST BOM_COST PROC
R 1
J 0
(-2200 1300);
PAINT MONO (-2200 1300);
DISPLAY INVISIBLE (-2200 1300);
FORCEPROP 2 LAST SEC_TYPE 0402
R 1
J 0
(-2400 1350);
DISPLAY 1.021277 (-2400 1350);
PAINT ORANGE (-2400 1350);
DISPLAY INVISIBLE (-2400 1350);
FORCEPROP 2 LAST SEC 1
R 1
J 0
(-2400 1350);
DISPLAY 0.680851 (-2400 1350);
PAINT MONO (-2400 1350);
DISPLAY INVISIBLE (-2400 1350);
FORCEPROP 2 LAST ROOM PROC_SIDEBAND
R 1
J 0
(-2125 1375);
DISPLAY 0.617021 (-2125 1375);
PAINT ORANGE (-2125 1375);
DISPLAY INVISIBLE (-2125 1375);
FORCEPROP 2 LAST CDS_LIB mstr_discrete
R 1
J 2
(-2200 1300);
PAINT ORANGE (-2200 1300);
DISPLAY INVISIBLE (-2200 1300);
FORCEADD OFFPAGE..1
(-3100 3150);
FORCEPROP 2 LAST $XR1 176 
J 0
(-3472 3150);
DISPLAY 0.638298 (-3472 3150);
PAINT MONO (-3472 3150);
FORCEPROP 2 LAST $XR0 158 
J 0
(-3352 3150);
DISPLAY 0.638298 (-3352 3150);
PAINT MONO (-3352 3150);
FORCEPROP 2 LAST PATH I14
J 0
(-3350 3225);
DISPLAY 1.021277 (-3350 3225);
PAINT ORANGE (-3350 3225);
DISPLAY INVISIBLE (-3350 3225);
FORCEPROP 2 LAST CDS_LIB mstr_standard
J 0
(-3100 3150);
PAINT ORANGE (-3100 3150);
DISPLAY INVISIBLE (-3100 3150);
FORCEPROP 1 LAST OFFPAGE TRUE
J 0
(-2775 3025);
DISPLAY 0.872340 (-2775 3025);
PAINT GREEN (-2775 3025);
DISPLAY INVISIBLE (-2775 3025);
FORCEPROP 1 LAST COMMENT_BODY TRUE
J 0
(-2975 3050);
DISPLAY 0.872340 (-2975 3050);
PAINT GREEN (-2975 3050);
DISPLAY INVISIBLE (-2975 3050);
FORCEADD OFFPAGE..5
(-3100 3100);
FORCEPROP 2 LAST $XR1 158 
J 0
(-3385 3064);
DISPLAY 0.638298 (-3385 3064);
PAINT MONO (-3385 3064);
FORCEPROP 2 LAST $XR0 176 
J 0
(-3385 3100);
DISPLAY 0.638298 (-3385 3100);
PAINT MONO (-3385 3100);
FORCEPROP 2 LAST PATH I15
J 0
(-3375 3150);
DISPLAY 1.021277 (-3375 3150);
PAINT ORANGE (-3375 3150);
DISPLAY INVISIBLE (-3375 3150);
FORCEPROP 2 LAST CDS_LIB mstr_standard
J 0
(-3100 3100);
PAINT ORANGE (-3100 3100);
DISPLAY INVISIBLE (-3100 3100);
FORCEPROP 1 LAST OFFPAGE TRUE
J 0
(-2775 2975);
DISPLAY 0.872340 (-2775 2975);
PAINT GREEN (-2775 2975);
DISPLAY INVISIBLE (-2775 2975);
FORCEPROP 1 LAST COMMENT_BODY TRUE
J 0
(-3000 3025);
DISPLAY 0.872340 (-3000 3025);
PAINT GREEN (-3000 3025);
DISPLAY INVISIBLE (-3000 3025);
FORCEADD OFFPAGE..5
(-2925 2900);
FORCEPROP 2 LAST $XR1 147 
J 0
(-3300 2900);
DISPLAY 0.638298 (-3300 2900);
PAINT MONO (-3300 2900);
FORCEPROP 2 LAST $XR0 161 
J 0
(-3180 2900);
DISPLAY 0.638298 (-3180 2900);
PAINT MONO (-3180 2900);
FORCEPROP 2 LAST PATH I16
J 0
(-3175 2950);
DISPLAY 1.021277 (-3175 2950);
PAINT ORANGE (-3175 2950);
DISPLAY INVISIBLE (-3175 2950);
FORCEPROP 2 LAST CDS_LIB mstr_standard
J 0
(-2925 2900);
PAINT ORANGE (-2925 2900);
DISPLAY INVISIBLE (-2925 2900);
FORCEPROP 1 LAST OFFPAGE TRUE
J 0
(-2600 2775);
DISPLAY 0.872340 (-2600 2775);
PAINT GREEN (-2600 2775);
DISPLAY INVISIBLE (-2600 2775);
FORCEPROP 1 LAST COMMENT_BODY TRUE
J 0
(-2825 2825);
DISPLAY 0.872340 (-2825 2825);
PAINT GREEN (-2825 2825);
DISPLAY INVISIBLE (-2825 2825);
FORCEADD OFFPAGE..5
(-2925 2950);
FORCEPROP 2 LAST $XR0 147 
J 0
(-3180 2950);
DISPLAY 0.638298 (-3180 2950);
PAINT MONO (-3180 2950);
FORCEPROP 2 LAST PATH I17
J 0
(-3175 3000);
DISPLAY 1.021277 (-3175 3000);
PAINT ORANGE (-3175 3000);
DISPLAY INVISIBLE (-3175 3000);
FORCEPROP 2 LAST CDS_LIB mstr_standard
J 0
(-2925 2950);
PAINT ORANGE (-2925 2950);
DISPLAY INVISIBLE (-2925 2950);
FORCEPROP 1 LAST OFFPAGE TRUE
J 0
(-2600 2825);
DISPLAY 0.872340 (-2600 2825);
PAINT GREEN (-2600 2825);
DISPLAY INVISIBLE (-2600 2825);
FORCEPROP 1 LAST COMMENT_BODY TRUE
J 0
(-2825 2875);
DISPLAY 0.872340 (-2825 2875);
PAINT GREEN (-2825 2875);
DISPLAY INVISIBLE (-2825 2875);
FORCEADD OFFPAGE..1
(-3125 3600);
FORCEPROP 2 LAST $XR0 158 
J 0
(-3377 3600);
DISPLAY 0.638298 (-3377 3600);
PAINT MONO (-3377 3600);
FORCEPROP 2 LAST PATH I18
J 0
(-3375 3650);
DISPLAY 1.021277 (-3375 3650);
PAINT ORANGE (-3375 3650);
DISPLAY INVISIBLE (-3375 3650);
FORCEPROP 2 LAST CDS_LIB mstr_standard
J 0
(-3125 3600);
PAINT ORANGE (-3125 3600);
DISPLAY INVISIBLE (-3125 3600);
FORCEPROP 1 LAST OFFPAGE TRUE
J 0
(-2800 3475);
DISPLAY 0.872340 (-2800 3475);
PAINT GREEN (-2800 3475);
DISPLAY INVISIBLE (-2800 3475);
FORCEPROP 1 LAST COMMENT_BODY TRUE
J 0
(-3000 3500);
DISPLAY 0.872340 (-3000 3500);
PAINT GREEN (-3000 3500);
DISPLAY INVISIBLE (-3000 3500);
FORCEADD OFFPAGE..5
(-3125 3550);
FORCEPROP 2 LAST $XR0 158 
J 0
(-3380 3550);
DISPLAY 0.638298 (-3380 3550);
PAINT MONO (-3380 3550);
FORCEPROP 2 LAST PATH I19
J 0
(-3375 3600);
DISPLAY 1.021277 (-3375 3600);
PAINT ORANGE (-3375 3600);
DISPLAY INVISIBLE (-3375 3600);
FORCEPROP 2 LAST CDS_LIB mstr_standard
J 0
(-3125 3550);
PAINT ORANGE (-3125 3550);
DISPLAY INVISIBLE (-3125 3550);
FORCEPROP 1 LAST OFFPAGE TRUE
J 0
(-2800 3425);
DISPLAY 0.872340 (-2800 3425);
PAINT GREEN (-2800 3425);
DISPLAY INVISIBLE (-2800 3425);
FORCEPROP 1 LAST COMMENT_BODY TRUE
J 0
(-3025 3475);
DISPLAY 0.872340 (-3025 3475);
PAINT GREEN (-3025 3475);
DISPLAY INVISIBLE (-3025 3475);
FORCEADD OFFPAGE..1
(-2375 3050);
FORCEPROP 2 LAST $XR1 198 
J 0
(-2777 3050);
DISPLAY 0.638298 (-2777 3050);
PAINT MONO (-2777 3050);
FORCEPROP 2 LAST $XR0 161 
J 0
(-2657 3050);
DISPLAY 0.638298 (-2657 3050);
PAINT MONO (-2657 3050);
FORCEPROP 2 LAST PATH I20
J 0
(-2650 3100);
DISPLAY 1.021277 (-2650 3100);
PAINT ORANGE (-2650 3100);
DISPLAY INVISIBLE (-2650 3100);
FORCEPROP 2 LAST CDS_LIB mstr_standard
J 0
(-2375 3050);
PAINT ORANGE (-2375 3050);
DISPLAY INVISIBLE (-2375 3050);
FORCEPROP 1 LAST OFFPAGE TRUE
J 0
(-2050 2925);
DISPLAY 0.872340 (-2050 2925);
PAINT GREEN (-2050 2925);
DISPLAY INVISIBLE (-2050 2925);
FORCEPROP 1 LAST COMMENT_BODY TRUE
J 0
(-2250 2950);
DISPLAY 0.872340 (-2250 2950);
PAINT GREEN (-2250 2950);
DISPLAY INVISIBLE (-2250 2950);
FORCEADD P12V_PSU..1
(-2200 1975);
FORCEPROP 3 LASTPIN (-2200 1925) SIG_NAME P12V_PSU\g
J 0
(-2190 1935);
DISPLAY 0.659574 (-2190 1935);
PAINT MONO (-2190 1935);
DISPLAY INVISIBLE (-2190 1935);
FORCEPROP 1 LAST HDL_POWER P12V_PSU
J 1
(-2200 2025);
DISPLAY 0.872340 (-2200 2025);
PAINT GREEN (-2200 2025);
DISPLAY INVISIBLE (-2200 2025);
FORCEPROP 1 LAST BODY_TYPE PLUMBING
J 0
(-2245 1932);
DISPLAY 0.340426 (-2245 1932);
PAINT GREEN (-2245 1932);
DISPLAY INVISIBLE (-2245 1932);
FORCEPROP 2 LAST CDS_LIB mstr_symbols
J 0
(-2200 1975);
PAINT ORANGE (-2200 1975);
DISPLAY INVISIBLE (-2200 1975);
FORCEPROP 2 LAST BOM_COST NT_BASE_VRD
J 0
(-2200 2075);
DISPLAY 0.617021 (-2200 2075);
PAINT ORANGE (-2200 2075);
DISPLAY INVISIBLE (-2200 2075);
FORCEPROP 2 LAST ROOM P2V5_LAN_AUX_VR
J 0
(-2200 2075);
DISPLAY 0.617021 (-2200 2075);
PAINT ORANGE (-2200 2075);
DISPLAY INVISIBLE (-2200 2075);
FORCEPROP 1 LAST VOLTAGE 12.0
J 0
(-2245 1932);
DISPLAY 0.340426 (-2245 1932);
PAINT SKYBLUE (-2245 1932);
DISPLAY INVISIBLE (-2245 1932);
FORCEPROP 1 LAST PATH I21
J 0
(-2150 2000);
DISPLAY 0.872340 (-2150 2000);
PAINT AQUA (-2150 2000);
DISPLAY INVISIBLE (-2150 2000);
FORCEADD RES..1
(-2225 2800);
FORCEPROP 1 LAST PACK_TYPE 0402
J 0
(-2125 2675);
DISPLAY 0.617021 (-2125 2675);
PAINT SKYBLUE (-2125 2675);
FORCEPROP 1 LAST MATERIAL CHIP
J 0
(-2250 2675);
DISPLAY 0.617021 (-2250 2675);
PAINT SKYBLUE (-2250 2675);
FORCEPROP 1 LAST TOLERANCE 5%
J 0
(-2325 2675);
DISPLAY 0.617021 (-2325 2675);
PAINT SKYBLUE (-2325 2675);
FORCEPROP 1 LAST WATTAGE 1/16W
J 0
(-2500 2675);
DISPLAY 0.617021 (-2500 2675);
PAINT SKYBLUE (-2500 2675);
FORCEPROP 1 LAST PART_NUMBER G21497-005
J 0
(-2625 2750);
DISPLAY 0.617021 (-2625 2750);
PAINT BLUE (-2625 2750);
FORCEPROP 1 LASTPIN (-2125 2800) $PN 2
J 0
(-2163 2812);
DISPLAY 0.617021 (-2163 2812);
PAINT ORANGE (-2163 2812);
FORCEPROP 1 LASTPIN (-2325 2800) $PN 1
J 0
(-2313 2812);
DISPLAY 0.617021 (-2313 2812);
PAINT ORANGE (-2313 2812);
FORCEPROP 1 LAST LOCATION R1F8
J 0
(-2475 2800);
DISPLAY 0.617021 (-2475 2800);
PAINT AQUA (-2475 2800);
FORCEPROP 1 LAST VALUE 0.0
J 2
(-1800 2800);
DISPLAY 0.617021 (-1800 2800);
PAINT SKYBLUE (-1800 2800);
FORCEPROP 1 LAST PATH I22
J 0
(-2275 2950);
DISPLAY 0.978723 (-2275 2950);
PAINT WHITE (-2275 2950);
DISPLAY INVISIBLE (-2275 2950);
FORCEPROP 0 LAST CDS_SEC 1
J 0
(-1800 2850);
PAINT MONO (-1800 2850);
DISPLAY INVISIBLE (-1800 2850);
FORCEPROP 2 LAST CDS_LOCATION R1F8
J 0
(-2475 2800);
DISPLAY 0.617021 (-2475 2800);
PAINT AQUA (-2475 2800);
DISPLAY INVISIBLE (-2475 2800);
FORCEPROP 2 LAST CDS_LIB mstr_discrete
J 0
(-2225 2800);
PAINT ORANGE (-2225 2800);
DISPLAY INVISIBLE (-2225 2800);
FORCEPROP 2 LAST SEC_TYPE 0402
J 0
(-2275 3000);
DISPLAY 1.021277 (-2275 3000);
PAINT ORANGE (-2275 3000);
DISPLAY INVISIBLE (-2275 3000);
FORCEPROP 2 LAST SEC 1
J 0
(-2275 3000);
DISPLAY 0.680851 (-2275 3000);
PAINT MONO (-2275 3000);
DISPLAY INVISIBLE (-2275 3000);
FORCEADD OFFPAGE..1
(-2000 2550);
FORCEPROP 2 LAST $XR0 114 
J 0
(-2252 2550);
DISPLAY 0.638298 (-2252 2550);
PAINT MONO (-2252 2550);
FORCEPROP 2 LAST PATH I23
J 0
(-2250 2600);
DISPLAY 1.021277 (-2250 2600);
PAINT ORANGE (-2250 2600);
DISPLAY INVISIBLE (-2250 2600);
FORCEPROP 2 LAST CDS_LIB mstr_standard
J 0
(-2000 2550);
PAINT ORANGE (-2000 2550);
DISPLAY INVISIBLE (-2000 2550);
FORCEPROP 1 LAST OFFPAGE TRUE
J 0
(-1675 2425);
DISPLAY 0.872340 (-1675 2425);
PAINT GREEN (-1675 2425);
DISPLAY INVISIBLE (-1675 2425);
FORCEPROP 1 LAST COMMENT_BODY TRUE
J 0
(-1875 2450);
DISPLAY 0.872340 (-1875 2450);
PAINT GREEN (-1875 2450);
DISPLAY INVISIBLE (-1875 2450);
FORCEADD OFFPAGE..1
(-2000 2600);
FORCEPROP 2 LAST $XR0 114 
J 0
(-2252 2600);
DISPLAY 0.638298 (-2252 2600);
PAINT MONO (-2252 2600);
FORCEPROP 2 LAST PATH I24
J 0
(-2250 2650);
DISPLAY 1.021277 (-2250 2650);
PAINT ORANGE (-2250 2650);
DISPLAY INVISIBLE (-2250 2650);
FORCEPROP 2 LAST CDS_LIB mstr_standard
J 0
(-2000 2600);
PAINT ORANGE (-2000 2600);
DISPLAY INVISIBLE (-2000 2600);
FORCEPROP 1 LAST OFFPAGE TRUE
J 0
(-1675 2475);
DISPLAY 0.872340 (-1675 2475);
PAINT GREEN (-1675 2475);
DISPLAY INVISIBLE (-1675 2475);
FORCEPROP 1 LAST COMMENT_BODY TRUE
J 0
(-1875 2500);
DISPLAY 0.872340 (-1875 2500);
PAINT GREEN (-1875 2500);
DISPLAY INVISIBLE (-1875 2500);
FORCEADD OFFPAGE..6
(-2000 2750);
FORCEPROP 2 LAST $XR0 181 
J 0
(-2280 2750);
DISPLAY 0.638298 (-2280 2750);
PAINT MONO (-2280 2750);
FORCEPROP 2 LAST PATH I25
J 0
(-2275 2800);
DISPLAY 1.021277 (-2275 2800);
PAINT ORANGE (-2275 2800);
DISPLAY INVISIBLE (-2275 2800);
FORCEPROP 2 LAST CDS_LIB mstr_standard
J 0
(-2000 2750);
PAINT ORANGE (-2000 2750);
DISPLAY INVISIBLE (-2000 2750);
FORCEPROP 1 LAST OFFPAGE TRUE
J 0
(-1675 2625);
DISPLAY 0.872340 (-1675 2625);
PAINT GREEN (-1675 2625);
DISPLAY INVISIBLE (-1675 2625);
FORCEPROP 1 LAST COMMENT_BODY TRUE
J 0
(-1900 2675);
DISPLAY 0.872340 (-1900 2675);
PAINT GREEN (-1900 2675);
DISPLAY INVISIBLE (-1900 2675);
FORCEADD RES..1
(-1500 2700);
FORCEPROP 1 LAST VALUE 0.0
J 2
(-1525 2650);
DISPLAY 0.617021 (-1525 2650);
PAINT SKYBLUE (-1525 2650);
FORCEPROP 1 LAST MATERIAL CHIP
J 0
(-1375 2650);
DISPLAY 0.617021 (-1375 2650);
PAINT SKYBLUE (-1375 2650);
FORCEPROP 1 LAST TOLERANCE 5%
J 0
(-1450 2650);
DISPLAY 0.617021 (-1450 2650);
PAINT SKYBLUE (-1450 2650);
FORCEPROP 1 LAST WATTAGE 1/16W
J 2
(-1625 2650);
DISPLAY 0.617021 (-1625 2650);
PAINT SKYBLUE (-1625 2650);
FORCEPROP 1 LAST PACK_TYPE 0402
J 0
(-1250 2650);
DISPLAY 0.617021 (-1250 2650);
PAINT SKYBLUE (-1250 2650);
FORCEPROP 1 LAST LOCATION R9T1
J 0
(-1550 2725);
DISPLAY 0.617021 (-1550 2725);
PAINT AQUA (-1550 2725);
FORCEPROP 1 LASTPIN (-1400 2700) $PN 2
J 0
(-1438 2712);
DISPLAY 0.617021 (-1438 2712);
PAINT ORANGE (-1438 2712);
FORCEPROP 1 LASTPIN (-1600 2700) $PN 1
J 0
(-1588 2712);
DISPLAY 0.617021 (-1588 2712);
PAINT ORANGE (-1588 2712);
FORCEPROP 1 LAST PART_NUMBER G21497-005
J 0
(-1375 2700);
DISPLAY 0.617021 (-1375 2700);
PAINT BLUE (-1375 2700);
FORCEPROP 1 LAST PATH I26
J 0
(-1550 2850);
DISPLAY 0.978723 (-1550 2850);
PAINT WHITE (-1550 2850);
DISPLAY INVISIBLE (-1550 2850);
FORCEPROP 0 LAST CDS_SEC 1
J 0
(-1550 2775);
PAINT MONO (-1550 2775);
DISPLAY INVISIBLE (-1550 2775);
FORCEPROP 2 LAST SEC 1
J 0
(-1550 2900);
DISPLAY 0.680851 (-1550 2900);
PAINT MONO (-1550 2900);
DISPLAY INVISIBLE (-1550 2900);
FORCEPROP 2 LAST SEC_TYPE 0402
J 0
(-1550 2900);
DISPLAY 1.021277 (-1550 2900);
PAINT ORANGE (-1550 2900);
DISPLAY INVISIBLE (-1550 2900);
FORCEPROP 2 LAST CDS_LIB mstr_discrete
J 0
(-1500 2700);
PAINT ORANGE (-1500 2700);
DISPLAY INVISIBLE (-1500 2700);
FORCEPROP 2 LAST CDS_LOCATION R9T1
J 0
(-1550 2725);
DISPLAY 0.617021 (-1550 2725);
PAINT AQUA (-1550 2725);
DISPLAY INVISIBLE (-1550 2725);
FORCEADD RES..1
(-2225 2900);
FORCEPROP 1 LAST VALUE 0.0
J 2
(-2250 2850);
DISPLAY 0.617021 (-2250 2850);
PAINT SKYBLUE (-2250 2850);
FORCEPROP 1 LAST WATTAGE 1/16W
J 2
(-2350 2850);
DISPLAY 0.617021 (-2350 2850);
PAINT SKYBLUE (-2350 2850);
FORCEPROP 1 LAST PART_NUMBER G21497-005
J 0
(-2125 2900);
DISPLAY 0.617021 (-2125 2900);
PAINT BLUE (-2125 2900);
FORCEPROP 1 LAST PACK_TYPE 0402
J 0
(-1975 2850);
DISPLAY 0.617021 (-1975 2850);
PAINT SKYBLUE (-1975 2850);
FORCEPROP 1 LASTPIN (-2325 2900) $PN 1
J 0
(-2313 2912);
DISPLAY 0.617021 (-2313 2912);
PAINT ORANGE (-2313 2912);
FORCEPROP 1 LAST TOLERANCE 5%
J 0
(-2175 2850);
DISPLAY 0.617021 (-2175 2850);
PAINT SKYBLUE (-2175 2850);
FORCEPROP 1 LAST LOCATION R9R12
J 0
(-2275 2950);
DISPLAY 0.617021 (-2275 2950);
PAINT AQUA (-2275 2950);
FORCEPROP 1 LASTPIN (-2125 2900) $PN 2
J 0
(-2163 2912);
DISPLAY 0.617021 (-2163 2912);
PAINT ORANGE (-2163 2912);
FORCEPROP 1 LAST MATERIAL CHIP
J 0
(-2100 2850);
DISPLAY 0.617021 (-2100 2850);
PAINT SKYBLUE (-2100 2850);
FORCEPROP 1 LAST PATH I27
J 0
(-2275 3050);
DISPLAY 0.978723 (-2275 3050);
PAINT WHITE (-2275 3050);
DISPLAY INVISIBLE (-2275 3050);
FORCEPROP 0 LAST CDS_SEC 1
J 0
(-2275 3000);
PAINT MONO (-2275 3000);
DISPLAY INVISIBLE (-2275 3000);
FORCEPROP 2 LAST CDS_LIB mstr_discrete
J 0
(-2225 2900);
PAINT ORANGE (-2225 2900);
DISPLAY INVISIBLE (-2225 2900);
FORCEPROP 2 LAST CDS_LOCATION R9R12
J 0
(-2275 2950);
DISPLAY 0.617021 (-2275 2950);
PAINT AQUA (-2275 2950);
DISPLAY INVISIBLE (-2275 2950);
FORCEPROP 2 LAST SEC 1
J 0
(-2275 3100);
DISPLAY 0.680851 (-2275 3100);
PAINT MONO (-2275 3100);
DISPLAY INVISIBLE (-2275 3100);
FORCEPROP 2 LAST SEC_TYPE 0402
J 0
(-2275 3100);
DISPLAY 1.021277 (-2275 3100);
PAINT ORANGE (-2275 3100);
DISPLAY INVISIBLE (-2275 3100);
FORCEADD RES..1
(-2125 3100);
FORCEPROP 1 LAST MATERIAL EMPTY
J 0
(-2375 3100);
DISPLAY 0.617021 (-2375 3100);
PAINT RED (-2375 3100);
FORCEPROP 1 LASTPIN (-2225 3100) $PN 1
J 0
(-2213 3112);
DISPLAY 0.617021 (-2213 3112);
PAINT ORANGE (-2213 3112);
FORCEPROP 1 LAST LOCATION R9F63
J 0
(-2175 3200);
DISPLAY 0.617021 (-2175 3200);
PAINT AQUA (-2175 3200);
FORCEPROP 1 LASTPIN (-2025 3100) $PN 2
J 0
(-2063 3112);
DISPLAY 0.617021 (-2063 3112);
PAINT ORANGE (-2063 3112);
FORCEPROP 1 LAST VALUE 0.0
J 2
(-2425 3000);
DISPLAY 0.617021 (-2425 3000);
PAINT SKYBLUE (-2425 3000);
FORCEPROP 1 LAST PART_NUMBER G21497-005
J 0
(-2325 3250);
DISPLAY 0.617021 (-2325 3250);
PAINT BLUE (-2325 3250);
FORCEPROP 1 LAST PATH I28
J 0
(-2175 3250);
DISPLAY 0.978723 (-2175 3250);
PAINT WHITE (-2175 3250);
DISPLAY INVISIBLE (-2175 3250);
FORCEPROP 0 LAST CDS_LOCATION R9F63
J 0
(-2175 3250);
PAINT MONO (-2175 3250);
DISPLAY INVISIBLE (-2175 3250);
FORCEPROP 0 LAST CDS_SEC 1
J 0
(-2175 3250);
PAINT MONO (-2175 3250);
DISPLAY INVISIBLE (-2175 3250);
FORCEPROP 1 LAST TOLERANCE 5%
J 0
(-2300 3300);
DISPLAY 0.617021 (-2300 3300);
PAINT SKYBLUE (-2300 3300);
DISPLAY INVISIBLE (-2300 3300);
FORCEPROP 1 LAST WATTAGE 1/16W
J 2
(-2200 3150);
DISPLAY 0.617021 (-2200 3150);
PAINT SKYBLUE (-2200 3150);
DISPLAY INVISIBLE (-2200 3150);
FORCEPROP 0 LAST ROOM UART_MUX
J 0
(-2175 3250);
DISPLAY 1.021277 (-2175 3250);
PAINT ORANGE (-2175 3250);
DISPLAY INVISIBLE (-2175 3250);
FORCEPROP 2 LAST SEC_TYPE 0402
J 0
(-2175 3300);
DISPLAY 1.021277 (-2175 3300);
PAINT ORANGE (-2175 3300);
DISPLAY INVISIBLE (-2175 3300);
FORCEPROP 0 LAST SEC 1
J 0
(-2175 3200);
DISPLAY 0.680851 (-2175 3200);
PAINT MONO (-2175 3200);
DISPLAY INVISIBLE (-2175 3200);
FORCEPROP 2 LAST CDS_LIB mstr_discrete
J 0
(-2125 3100);
PAINT ORANGE (-2125 3100);
DISPLAY INVISIBLE (-2125 3100);
FORCEPROP 1 LAST PACK_TYPE 0402
J 0
(-1875 2950);
DISPLAY 0.617021 (-1875 2950);
PAINT SKYBLUE (-1875 2950);
DISPLAY INVISIBLE (-1875 2950);
FORCEADD RES..1
(-2175 3550);
FORCEPROP 1 LAST TOLERANCE 5%
J 0
(-2075 3625);
DISPLAY 0.617021 (-2075 3625);
PAINT SKYBLUE (-2075 3625);
FORCEPROP 1 LAST VALUE 0.0
J 2
(-2100 3625);
DISPLAY 0.617021 (-2100 3625);
PAINT SKYBLUE (-2100 3625);
FORCEPROP 1 LASTPIN (-2075 3550) $PN 2
J 0
(-2113 3562);
DISPLAY 0.617021 (-2113 3562);
PAINT ORANGE (-2113 3562);
FORCEPROP 1 LAST PACK_TYPE 0402
J 0
(-1950 3500);
DISPLAY 0.617021 (-1950 3500);
PAINT SKYBLUE (-1950 3500);
FORCEPROP 1 LASTPIN (-2275 3550) $PN 1
J 0
(-2263 3562);
DISPLAY 0.617021 (-2263 3562);
PAINT ORANGE (-2263 3562);
FORCEPROP 1 LAST LOCATION R9F64
J 0
(-2350 3625);
DISPLAY 0.617021 (-2350 3625);
PAINT AQUA (-2350 3625);
FORCEPROP 1 LAST PART_NUMBER G21497-005
J 0
(-2375 3500);
DISPLAY 0.617021 (-2375 3500);
PAINT BLUE (-2375 3500);
FORCEPROP 1 LAST WATTAGE 1/16W
J 0
(-2100 3500);
DISPLAY 0.617021 (-2100 3500);
PAINT SKYBLUE (-2100 3500);
FORCEPROP 1 LAST MATERIAL CHIP
J 0
(-2400 3550);
DISPLAY 0.617021 (-2400 3550);
PAINT SKYBLUE (-2400 3550);
FORCEPROP 1 LAST PATH I29
J 0
(-2225 3700);
DISPLAY 0.978723 (-2225 3700);
PAINT WHITE (-2225 3700);
DISPLAY INVISIBLE (-2225 3700);
FORCEPROP 0 LAST CDS_LOCATION R9F64
J 0
(-2500 3700);
PAINT MONO (-2500 3700);
DISPLAY INVISIBLE (-2500 3700);
FORCEPROP 2 LAST SEC_TYPE 0402
J 0
(-2225 3750);
DISPLAY 1.021277 (-2225 3750);
PAINT ORANGE (-2225 3750);
DISPLAY INVISIBLE (-2225 3750);
FORCEPROP 0 LAST ROOM UART_MUX
J 0
(-2500 3750);
DISPLAY 1.021277 (-2500 3750);
PAINT ORANGE (-2500 3750);
DISPLAY INVISIBLE (-2500 3750);
FORCEPROP 2 LAST CDS_LIB mstr_discrete
J 0
(-2175 3550);
PAINT ORANGE (-2175 3550);
DISPLAY INVISIBLE (-2175 3550);
FORCEPROP 0 LAST SEC 1
J 0
(-2500 3700);
DISPLAY 0.680851 (-2500 3700);
PAINT MONO (-2500 3700);
DISPLAY INVISIBLE (-2500 3700);
FORCEPROP 0 LAST CDS_SEC 1
J 0
(-2500 3700);
PAINT MONO (-2500 3700);
DISPLAY INVISIBLE (-2500 3700);
FORCEADD RES..1
(-1750 3150);
FORCEPROP 1 LAST TOLERANCE 5%
J 0
(-1600 3100);
DISPLAY 0.617021 (-1600 3100);
PAINT SKYBLUE (-1600 3100);
FORCEPROP 1 LAST PART_NUMBER G21497-005
J 0
(-1750 3300);
DISPLAY 0.617021 (-1750 3300);
PAINT BLUE (-1750 3300);
FORCEPROP 1 LAST MATERIAL EMPTY
J 0
(-2000 3150);
DISPLAY 0.617021 (-2000 3150);
PAINT RED (-2000 3150);
FORCEPROP 1 LAST LOCATION R9F70
J 0
(-1775 3225);
DISPLAY 0.617021 (-1775 3225);
PAINT AQUA (-1775 3225);
FORCEPROP 1 LASTPIN (-1650 3150) $PN 2
J 0
(-1688 3162);
DISPLAY 0.617021 (-1688 3162);
PAINT ORANGE (-1688 3162);
FORCEPROP 1 LASTPIN (-1850 3150) $PN 1
J 0
(-1838 3162);
DISPLAY 0.617021 (-1838 3162);
PAINT ORANGE (-1838 3162);
FORCEPROP 1 LAST VALUE 0.0
J 2
(-1425 3100);
DISPLAY 0.617021 (-1425 3100);
PAINT SKYBLUE (-1425 3100);
FORCEPROP 1 LAST WATTAGE 1/16W
J 2
(-1900 3100);
DISPLAY 0.617021 (-1900 3100);
PAINT SKYBLUE (-1900 3100);
FORCEPROP 1 LAST PATH I30
J 0
(-1800 3300);
DISPLAY 0.978723 (-1800 3300);
PAINT WHITE (-1800 3300);
DISPLAY INVISIBLE (-1800 3300);
FORCEPROP 0 LAST CDS_LOCATION R9F70
J 0
(-1825 3300);
PAINT MONO (-1825 3300);
DISPLAY INVISIBLE (-1825 3300);
FORCEPROP 0 LAST CDS_SEC 1
J 0
(-1825 3300);
PAINT MONO (-1825 3300);
DISPLAY INVISIBLE (-1825 3300);
FORCEPROP 2 LAST CDS_LIB mstr_discrete
J 0
(-1750 3150);
PAINT ORANGE (-1750 3150);
DISPLAY INVISIBLE (-1750 3150);
FORCEPROP 0 LAST SEC 1
J 0
(-1800 3250);
DISPLAY 0.680851 (-1800 3250);
PAINT MONO (-1800 3250);
DISPLAY INVISIBLE (-1800 3250);
FORCEPROP 2 LAST SEC_TYPE 0402
J 0
(-1800 3350);
DISPLAY 1.021277 (-1800 3350);
PAINT ORANGE (-1800 3350);
DISPLAY INVISIBLE (-1800 3350);
FORCEPROP 0 LAST ROOM UART_MUX
J 0
(-1800 3300);
DISPLAY 1.021277 (-1800 3300);
PAINT ORANGE (-1800 3300);
DISPLAY INVISIBLE (-1800 3300);
FORCEPROP 1 LAST PACK_TYPE 0402
J 0
(-1500 3000);
DISPLAY 0.617021 (-1500 3000);
PAINT SKYBLUE (-1500 3000);
DISPLAY INVISIBLE (-1500 3000);
FORCEADD RES..1
(-1525 2850);
FORCEPROP 1 LAST WATTAGE 1/16W
J 2
(-1650 2800);
DISPLAY 0.617021 (-1650 2800);
PAINT SKYBLUE (-1650 2800);
FORCEPROP 1 LAST MATERIAL CHIP
J 0
(-1400 2800);
DISPLAY 0.617021 (-1400 2800);
PAINT SKYBLUE (-1400 2800);
FORCEPROP 1 LASTPIN (-1625 2850) $PN 1
J 0
(-1613 2862);
DISPLAY 0.617021 (-1613 2862);
PAINT ORANGE (-1613 2862);
FORCEPROP 1 LASTPIN (-1425 2850) $PN 2
J 0
(-1463 2862);
DISPLAY 0.617021 (-1463 2862);
PAINT ORANGE (-1463 2862);
FORCEPROP 1 LAST LOCATION R9R10
J 0
(-1575 2875);
DISPLAY 0.617021 (-1575 2875);
PAINT AQUA (-1575 2875);
FORCEPROP 1 LAST PACK_TYPE 0402
J 0
(-1275 2800);
DISPLAY 0.617021 (-1275 2800);
PAINT SKYBLUE (-1275 2800);
FORCEPROP 1 LAST TOLERANCE 5%
J 0
(-1475 2800);
DISPLAY 0.617021 (-1475 2800);
PAINT SKYBLUE (-1475 2800);
FORCEPROP 1 LAST PART_NUMBER G21497-005
J 0
(-1425 2850);
DISPLAY 0.617021 (-1425 2850);
PAINT BLUE (-1425 2850);
FORCEPROP 1 LAST VALUE 0.0
J 2
(-1550 2800);
DISPLAY 0.617021 (-1550 2800);
PAINT SKYBLUE (-1550 2800);
FORCEPROP 1 LAST PATH I31
J 0
(-1575 3000);
DISPLAY 0.978723 (-1575 3000);
PAINT WHITE (-1575 3000);
DISPLAY INVISIBLE (-1575 3000);
FORCEPROP 0 LAST CDS_SEC 1
J 0
(-1575 2925);
PAINT MONO (-1575 2925);
DISPLAY INVISIBLE (-1575 2925);
FORCEPROP 2 LAST CDS_LIB mstr_discrete
J 0
(-1525 2850);
PAINT ORANGE (-1525 2850);
DISPLAY INVISIBLE (-1525 2850);
FORCEPROP 2 LAST CDS_LOCATION R9R10
J 0
(-1575 2875);
DISPLAY 0.617021 (-1575 2875);
PAINT AQUA (-1575 2875);
DISPLAY INVISIBLE (-1575 2875);
FORCEPROP 2 LAST SEC_TYPE 0402
J 0
(-1575 3050);
DISPLAY 1.021277 (-1575 3050);
PAINT ORANGE (-1575 3050);
DISPLAY INVISIBLE (-1575 3050);
FORCEPROP 2 LAST SEC 1
J 0
(-1575 3050);
DISPLAY 0.680851 (-1575 3050);
PAINT MONO (-1575 3050);
DISPLAY INVISIBLE (-1575 3050);
FORCEADD RES..1
(-1525 2950);
FORCEPROP 1 LAST WATTAGE 1/16W
J 2
(-1650 2900);
DISPLAY 0.617021 (-1650 2900);
PAINT SKYBLUE (-1650 2900);
FORCEPROP 1 LAST TOLERANCE 5%
J 0
(-1475 2900);
DISPLAY 0.617021 (-1475 2900);
PAINT SKYBLUE (-1475 2900);
FORCEPROP 1 LAST PACK_TYPE 0402
J 0
(-1275 2900);
DISPLAY 0.617021 (-1275 2900);
PAINT SKYBLUE (-1275 2900);
FORCEPROP 1 LAST MATERIAL CHIP
J 0
(-1400 2900);
DISPLAY 0.617021 (-1400 2900);
PAINT SKYBLUE (-1400 2900);
FORCEPROP 1 LASTPIN (-1425 2950) $PN 2
J 0
(-1463 2962);
DISPLAY 0.617021 (-1463 2962);
PAINT ORANGE (-1463 2962);
FORCEPROP 1 LAST PART_NUMBER G21497-005
J 0
(-1425 2950);
DISPLAY 0.617021 (-1425 2950);
PAINT BLUE (-1425 2950);
FORCEPROP 1 LAST LOCATION R9R9
J 0
(-1750 2950);
DISPLAY 0.617021 (-1750 2950);
PAINT AQUA (-1750 2950);
FORCEPROP 1 LASTPIN (-1625 2950) $PN 1
J 0
(-1613 2962);
DISPLAY 0.617021 (-1613 2962);
PAINT ORANGE (-1613 2962);
FORCEPROP 1 LAST VALUE 0.0
J 2
(-1550 2900);
DISPLAY 0.617021 (-1550 2900);
PAINT SKYBLUE (-1550 2900);
FORCEPROP 1 LAST PATH I32
J 0
(-1575 3100);
DISPLAY 0.978723 (-1575 3100);
PAINT WHITE (-1575 3100);
DISPLAY INVISIBLE (-1575 3100);
FORCEPROP 0 LAST CDS_SEC 1
J 0
(-1425 3000);
PAINT MONO (-1425 3000);
DISPLAY INVISIBLE (-1425 3000);
FORCEPROP 2 LAST CDS_LIB mstr_discrete
J 0
(-1525 2950);
PAINT ORANGE (-1525 2950);
DISPLAY INVISIBLE (-1525 2950);
FORCEPROP 2 LAST CDS_LOCATION R9R9
J 0
(-1550 3000);
DISPLAY 0.617021 (-1550 3000);
PAINT AQUA (-1550 3000);
DISPLAY INVISIBLE (-1550 3000);
FORCEPROP 2 LAST SEC_TYPE 0402
J 0
(-1575 3150);
DISPLAY 1.021277 (-1575 3150);
PAINT ORANGE (-1575 3150);
DISPLAY INVISIBLE (-1575 3150);
FORCEPROP 2 LAST SEC 1
J 0
(-1575 3150);
DISPLAY 0.680851 (-1575 3150);
PAINT MONO (-1575 3150);
DISPLAY INVISIBLE (-1575 3150);
FORCEADD RES..1
(-1775 3600);
FORCEPROP 1 LAST MATERIAL CHIP
J 0
(-1650 3500);
DISPLAY 0.617021 (-1650 3500);
PAINT SKYBLUE (-1650 3500);
FORCEPROP 1 LAST PART_NUMBER G21497-005
J 0
(-1700 3600);
DISPLAY 0.617021 (-1700 3600);
PAINT BLUE (-1700 3600);
FORCEPROP 1 LAST WATTAGE 1/16W
J 2
(-1425 3650);
DISPLAY 0.617021 (-1425 3650);
PAINT SKYBLUE (-1425 3650);
FORCEPROP 1 LAST TOLERANCE 5%
J 0
(-1650 3650);
DISPLAY 0.617021 (-1650 3650);
PAINT SKYBLUE (-1650 3650);
FORCEPROP 1 LAST LOCATION R9F67
J 0
(-1925 3650);
DISPLAY 0.617021 (-1925 3650);
PAINT AQUA (-1925 3650);
FORCEPROP 1 LAST VALUE 0.0
J 2
(-1700 3650);
DISPLAY 0.617021 (-1700 3650);
PAINT SKYBLUE (-1700 3650);
FORCEPROP 1 LAST PACK_TYPE 0402
J 0
(-1675 3550);
DISPLAY 0.617021 (-1675 3550);
PAINT SKYBLUE (-1675 3550);
FORCEPROP 1 LAST PATH I33
J 0
(-1825 3750);
DISPLAY 0.978723 (-1825 3750);
PAINT WHITE (-1825 3750);
DISPLAY INVISIBLE (-1825 3750);
FORCEPROP 0 LAST CDS_LOCATION R9F67
J 0
(-1825 3700);
PAINT MONO (-1825 3700);
DISPLAY INVISIBLE (-1825 3700);
FORCEPROP 0 LAST ROOM UART_MUX
J 0
(-1825 3750);
DISPLAY 1.021277 (-1825 3750);
PAINT ORANGE (-1825 3750);
DISPLAY INVISIBLE (-1825 3750);
FORCEPROP 1 LASTPIN (-1675 3600) $PN 2
J 0
(-1713 3612);
DISPLAY 0.787234 (-1713 3612);
PAINT ORANGE (-1713 3612);
DISPLAY INVISIBLE (-1713 3612);
FORCEPROP 2 LAST CDS_LIB mstr_discrete
J 0
(-1775 3600);
PAINT ORANGE (-1775 3600);
DISPLAY INVISIBLE (-1775 3600);
FORCEPROP 1 LASTPIN (-1875 3600) $PN 1
J 0
(-1863 3612);
DISPLAY 0.787234 (-1863 3612);
PAINT ORANGE (-1863 3612);
DISPLAY INVISIBLE (-1863 3612);
FORCEPROP 0 LAST $SEC 1
J 0
(-1825 3700);
PAINT MONO (-1825 3700);
DISPLAY INVISIBLE (-1825 3700);
FORCEPROP 0 LAST CDS_SEC 1
J 0
(-1825 3700);
PAINT MONO (-1825 3700);
DISPLAY INVISIBLE (-1825 3700);
FORCEADD CAP_A..1
(-700 800);
FORCEPROP 1 LAST VALUE 0.1UF
J 0
(-650 850);
DISPLAY 0.617021 (-650 850);
PAINT SKYBLUE (-650 850);
FORCEPROP 1 LAST TOLERANCE 10%
J 0
(-650 750);
DISPLAY 0.617021 (-650 750);
PAINT SKYBLUE (-650 750);
FORCEPROP 1 LAST MATERIAL X7R
J 0
(-650 700);
DISPLAY 0.617021 (-650 700);
PAINT SKYBLUE (-650 700);
FORCEPROP 1 LASTPIN (-700 700) $PN 2
J 0
(-690 680);
DISPLAY 0.617021 (-690 680);
PAINT ORANGE (-690 680);
FORCEPROP 1 LAST PART_NUMBER A36096-030
J 0
(-650 650);
DISPLAY 0.617021 (-650 650);
PAINT BLUE (-650 650);
FORCEPROP 1 LASTPIN (-700 900) $PN 1
J 0
(-690 880);
DISPLAY 0.617021 (-690 880);
PAINT ORANGE (-690 880);
FORCEPROP 1 LAST VOLTAGE 16V
J 0
(-650 800);
DISPLAY 0.617021 (-650 800);
PAINT SKYBLUE (-650 800);
FORCEPROP 1 LAST LOCATION C8E1
J 0
(-650 900);
DISPLAY 0.617021 (-650 900);
PAINT AQUA (-650 900);
FORCEPROP 1 LAST PACK_TYPE 0402V
J 0
(-650 600);
DISPLAY 0.617021 (-650 600);
PAINT SKYBLUE (-650 600);
FORCEPROP 1 LAST PATH I34
J 0
(-650 950);
DISPLAY 0.978723 (-650 950);
PAINT WHITE (-650 950);
DISPLAY INVISIBLE (-650 950);
FORCEPROP 2 LAST CDS_LOCATION C8E1
J 0
(-650 900);
DISPLAY 0.617021 (-650 900);
PAINT AQUA (-650 900);
DISPLAY INVISIBLE (-650 900);
FORCEPROP 2 LAST CDS_LIB dev_discrete
J 0
(-700 800);
PAINT ORANGE (-700 800);
DISPLAY INVISIBLE (-700 800);
FORCEPROP 2 LAST BOM_COST IO_SLOT
J 0
(-650 1000);
DISPLAY 1.021277 (-650 1000);
PAINT ORANGE (-650 1000);
DISPLAY INVISIBLE (-650 1000);
FORCEPROP 2 LAST CDS_SEC 1
J 0
(-650 950);
PAINT ORANGE (-650 950);
DISPLAY INVISIBLE (-650 950);
FORCEPROP 2 LAST SEC_TYPE 0402V
J 0
(-650 1000);
DISPLAY 1.021277 (-650 1000);
PAINT ORANGE (-650 1000);
DISPLAY INVISIBLE (-650 1000);
FORCEPROP 2 LAST SEC 1
J 0
(-650 950);
DISPLAY 0.680851 (-650 950);
PAINT MONO (-650 950);
DISPLAY INVISIBLE (-650 950);
FORCEPROP 2 LAST ROOM IO_SLOT
J 0
(-650 950);
DISPLAY 1.021277 (-650 950);
PAINT ORANGE (-650 950);
DISPLAY INVISIBLE (-650 950);
FORCEADD GND..1
(-700 500);
FORCEPROP 3 LASTPIN (-700 550) SIG_NAME GND\g
J 0
(-690 560);
DISPLAY 0.659574 (-690 560);
PAINT MONO (-690 560);
DISPLAY INVISIBLE (-690 560);
FORCEPROP 1 LAST PATH I35
J 0
(-625 500);
DISPLAY 0.872340 (-625 500);
PAINT AQUA (-625 500);
DISPLAY INVISIBLE (-625 500);
FORCEPROP 1 LAST VOLTAGE 0.0V
J 0
(-745 457);
DISPLAY 0.340426 (-745 457);
PAINT SKYBLUE (-745 457);
DISPLAY INVISIBLE (-745 457);
FORCEPROP 2 LAST CDS_LIB mstr_symbols
J 0
(-700 500);
PAINT ORANGE (-700 500);
DISPLAY INVISIBLE (-700 500);
FORCEPROP 1 LAST SIZE 1B
J 0
(-625 450);
DISPLAY 0.872340 (-625 450);
PAINT AQUA (-625 450);
DISPLAY INVISIBLE (-625 450);
FORCEPROP 1 LAST BODY_TYPE PLUMBING
J 0
(-745 457);
DISPLAY 0.340426 (-745 457);
PAINT GREEN (-745 457);
DISPLAY INVISIBLE (-745 457);
FORCEPROP 1 LAST HDL_POWER GND
J 0
(-700 650);
DISPLAY 0.872340 (-700 650);
PAINT GREEN (-700 650);
DISPLAY INVISIBLE (-700 650);
FORCEADD P3V3_STBY..1
(-700 1100);
FORCEPROP 3 LASTPIN (-700 1050) SIG_NAME P3V3_STBY\g
J 0
(-690 1060);
DISPLAY 0.659574 (-690 1060);
PAINT MONO (-690 1060);
DISPLAY INVISIBLE (-690 1060);
FORCEPROP 1 LAST PATH I36
J 0
(-655 1102);
DISPLAY 0.340426 (-655 1102);
PAINT GREEN (-655 1102);
DISPLAY INVISIBLE (-655 1102);
FORCEPROP 1 LAST VOLTAGE 3.3V
J 0
(-745 1057);
DISPLAY 0.340426 (-745 1057);
PAINT SKYBLUE (-745 1057);
DISPLAY INVISIBLE (-745 1057);
FORCEPROP 2 LAST CDS_LIB mstr_symbols
J 0
(-700 1100);
PAINT ORANGE (-700 1100);
DISPLAY INVISIBLE (-700 1100);
FORCEPROP 1 LAST SIZE 1B
J 0
(-655 1122);
DISPLAY 0.340426 (-655 1122);
PAINT GREEN (-655 1122);
DISPLAY INVISIBLE (-655 1122);
FORCEPROP 1 LAST BODY_TYPE PLUMBING
J 0
(-745 1057);
DISPLAY 0.340426 (-745 1057);
PAINT GREEN (-745 1057);
DISPLAY INVISIBLE (-745 1057);
FORCEPROP 1 LAST HDL_POWER P3V3_STBY
J 0
(-1000 975);
DISPLAY 0.872340 (-1000 975);
PAINT ORANGE (-1000 975);
DISPLAY INVISIBLE (-1000 975);
FORCEADD DIODE..1
(-425 1550);
FORCEPROP 1 LASTPIN (-525 1550) $PN 2
J 2
(-490 1560);
DISPLAY 0.617021 (-490 1560);
PAINT AQUA (-490 1560);
FORCEPROP 1 LASTPIN (-325 1550) $PN 1
J 0
(-360 1560);
DISPLAY 0.617021 (-360 1560);
PAINT AQUA (-360 1560);
FORCEPROP 1 LAST PART_NUMBER H71799-001
J 0
(-450 1650);
DISPLAY 0.617021 (-450 1650);
PAINT BLUE (-450 1650);
FORCEPROP 1 LAST LOCATION CR1F3
J 0
(-452 1706);
DISPLAY 0.617021 (-452 1706);
PAINT AQUA (-452 1706);
FORCEPROP 1 LAST VALUE SDMK0340L
J 0
(-450 1425);
DISPLAY 0.617021 (-450 1425);
PAINT SKYBLUE (-450 1425);
FORCEPROP 1 LAST MATERIAL IC
J 0
(-450 1372);
DISPLAY 0.617021 (-450 1372);
PAINT SKYBLUE (-450 1372);
FORCEPROP 1 LAST PACK_TYPE SM
J 0
(-450 1310);
DISPLAY 0.617021 (-450 1310);
PAINT SKYBLUE (-450 1310);
FORCEPROP 1 LAST PATH I37
J 0
(-445 1760);
DISPLAY 0.978723 (-445 1760);
PAINT PINK (-445 1760);
DISPLAY INVISIBLE (-445 1760);
FORCEPROP 0 LAST CDS_SEC 1
J 0
(-450 1750);
PAINT MONO (-450 1750);
DISPLAY INVISIBLE (-450 1750);
FORCEPROP 2 LAST CDS_LIB mstr_discrete
J 0
(-425 1550);
PAINT ORANGE (-425 1550);
DISPLAY INVISIBLE (-425 1550);
FORCEPROP 2 LAST CDS_LOCATION CR1F3
J 0
(-452 1706);
DISPLAY 0.617021 (-452 1706);
PAINT AQUA (-452 1706);
DISPLAY INVISIBLE (-452 1706);
FORCEPROP 2 LAST SEC 1
J 0
(-425 1825);
DISPLAY 0.680851 (-425 1825);
PAINT MONO (-425 1825);
DISPLAY INVISIBLE (-425 1825);
FORCEPROP 0 LAST BOM_COST IO_SLOT
J 0
(-450 1900);
DISPLAY 1.021277 (-450 1900);
PAINT ORANGE (-450 1900);
DISPLAY INVISIBLE (-450 1900);
FORCEPROP 2 LAST SEC_TYPE SM
J 0
(-425 1825);
DISPLAY 1.021277 (-425 1825);
PAINT ORANGE (-425 1825);
DISPLAY INVISIBLE (-425 1825);
FORCEPROP 0 LAST ROOM IO_SLOT
J 0
(-450 1800);
DISPLAY 1.021277 (-450 1800);
PAINT ORANGE (-450 1800);
DISPLAY INVISIBLE (-450 1800);
FORCEADD OFFPAGE..1
(0 775);
FORCEPROP 2 LAST $XR2 248 
J 0
(-492 775);
DISPLAY 0.638298 (-492 775);
PAINT MONO (-492 775);
FORCEPROP 2 LAST $XR1 241 
J 0
(-372 775);
DISPLAY 0.638298 (-372 775);
PAINT MONO (-372 775);
FORCEPROP 2 LAST $XR0 196 
J 0
(-252 775);
DISPLAY 0.638298 (-252 775);
PAINT MONO (-252 775);
FORCEPROP 2 LAST PATH I38
J 0
(-250 825);
DISPLAY 1.021277 (-250 825);
PAINT ORANGE (-250 825);
DISPLAY INVISIBLE (-250 825);
FORCEPROP 2 LAST CDS_LIB mstr_standard
J 0
(0 775);
PAINT ORANGE (0 775);
DISPLAY INVISIBLE (0 775);
FORCEPROP 1 LAST OFFPAGE TRUE
J 0
(325 650);
DISPLAY 0.872340 (325 650);
PAINT GREEN (325 650);
DISPLAY INVISIBLE (325 650);
FORCEPROP 1 LAST COMMENT_BODY TRUE
J 0
(125 675);
DISPLAY 0.872340 (125 675);
PAINT GREEN (125 675);
DISPLAY INVISIBLE (125 675);
FORCEADD GND..1
(300 450);
FORCEPROP 3 LASTPIN (300 500) SIG_NAME GND\g
J 0
(310 510);
DISPLAY 0.659574 (310 510);
PAINT MONO (310 510);
DISPLAY INVISIBLE (310 510);
FORCEPROP 1 LAST PATH I39
J 0
(375 450);
DISPLAY 0.872340 (375 450);
PAINT AQUA (375 450);
DISPLAY INVISIBLE (375 450);
FORCEPROP 2 LAST ROOM P2V5_LAN_AUX_VR
J 0
(0 525);
DISPLAY 0.617021 (0 525);
PAINT ORANGE (0 525);
DISPLAY INVISIBLE (0 525);
FORCEPROP 2 LAST BOM_COST NT_BASE_VRD
J 0
(0 525);
DISPLAY 0.617021 (0 525);
PAINT ORANGE (0 525);
DISPLAY INVISIBLE (0 525);
FORCEPROP 1 LAST VOLTAGE 0
J 0
(300 450);
PAINT SKYBLUE (300 450);
DISPLAY INVISIBLE (300 450);
FORCEPROP 2 LAST CDS_LIB mstr_symbols
J 0
(300 450);
PAINT ORANGE (300 450);
DISPLAY INVISIBLE (300 450);
FORCEPROP 1 LAST SIZE 1B
J 0
(375 400);
DISPLAY 0.872340 (375 400);
PAINT GREEN (375 400);
DISPLAY INVISIBLE (375 400);
FORCEPROP 1 LAST BODY_TYPE PLUMBING
J 0
(255 407);
DISPLAY 0.340426 (255 407);
PAINT GREEN (255 407);
DISPLAY INVISIBLE (255 407);
FORCEPROP 1 LAST HDL_POWER GND
J 0
(300 600);
DISPLAY 0.872340 (300 600);
PAINT GREEN (300 600);
DISPLAY INVISIBLE (300 600);
FORCEADD RES..2
(-2200 1750);
FORCEPROP 1 LASTPIN (-2200 1650) $PN 2
J 0
(-2195 1660);
DISPLAY 0.617021 (-2195 1660);
PAINT ORANGE (-2195 1660);
FORCEPROP 1 LAST MATERIAL CHIP
J 0
(-2160 1675);
DISPLAY 0.617021 (-2160 1675);
PAINT SKYBLUE (-2160 1675);
FORCEPROP 1 LAST WATTAGE 1/16W
J 0
(-2160 1725);
DISPLAY 0.617021 (-2160 1725);
PAINT SKYBLUE (-2160 1725);
FORCEPROP 1 LASTPIN (-2200 1850) $PN 1
J 0
(-2195 1812);
DISPLAY 0.617021 (-2195 1812);
PAINT ORANGE (-2195 1812);
FORCEPROP 1 LAST LOCATION R9T9
J 0
(-2155 1875);
DISPLAY 0.617021 (-2155 1875);
PAINT AQUA (-2155 1875);
FORCEPROP 1 LAST TOLERANCE 1%
J 0
(-2155 1775);
DISPLAY 0.617021 (-2155 1775);
PAINT SKYBLUE (-2155 1775);
FORCEPROP 1 LAST VALUE 4.75K
J 0
(-2155 1825);
DISPLAY 0.617021 (-2155 1825);
PAINT SKYBLUE (-2155 1825);
FORCEPROP 1 LAST PART_NUMBER G21796-072
J 0
(-2160 1625);
DISPLAY 0.617021 (-2160 1625);
PAINT BLUE (-2160 1625);
FORCEPROP 1 LAST PACK_TYPE 0402
J 0
(-2160 1575);
DISPLAY 0.617021 (-2160 1575);
PAINT SKYBLUE (-2160 1575);
FORCEPROP 2 LAST CDS_LOCATION R9T9
J 0
(-2155 1875);
DISPLAY 0.617021 (-2155 1875);
PAINT AQUA (-2155 1875);
DISPLAY INVISIBLE (-2155 1875);
FORCEPROP 2 LAST SEC 1
J 0
(-2150 1975);
DISPLAY 0.680851 (-2150 1975);
PAINT MONO (-2150 1975);
DISPLAY INVISIBLE (-2150 1975);
FORCEPROP 2 LAST SEC_TYPE 0402
J 0
(-2150 1975);
DISPLAY 1.021277 (-2150 1975);
PAINT ORANGE (-2150 1975);
DISPLAY INVISIBLE (-2150 1975);
FORCEPROP 0 LAST BOM_COST IO_SLOT
J 0
(-2150 2075);
DISPLAY 1.021277 (-2150 2075);
PAINT ORANGE (-2150 2075);
DISPLAY INVISIBLE (-2150 2075);
FORCEPROP 0 LAST ROOM IO_SLOT
J 0
(-2150 1975);
DISPLAY 1.021277 (-2150 1975);
PAINT ORANGE (-2150 1975);
DISPLAY INVISIBLE (-2150 1975);
FORCEPROP 2 LAST CDS_LIB mstr_discrete
J 0
(-2200 1750);
PAINT MONO (-2200 1750);
DISPLAY INVISIBLE (-2200 1750);
FORCEPROP 0 LAST CDS_SEC 1
J 0
(-2150 1925);
PAINT MONO (-2150 1925);
DISPLAY INVISIBLE (-2150 1925);
FORCEPROP 1 LAST PATH I4
J 0
(-2150 1925);
DISPLAY 0.978723 (-2150 1925);
PAINT WHITE (-2150 1925);
DISPLAY INVISIBLE (-2150 1925);
FORCEADD CAP..1
(300 625);
FORCEPROP 1 LAST VOLTAGE 50V
J 0
(350 625);
DISPLAY 0.617021 (350 625);
PAINT SKYBLUE (350 625);
FORCEPROP 1 LAST VALUE 470PF
J 0
(350 675);
DISPLAY 0.617021 (350 675);
PAINT SKYBLUE (350 675);
FORCEPROP 1 LASTPIN (300 725) $PN 1
J 0
(310 705);
DISPLAY 0.617021 (310 705);
PAINT ORANGE (310 705);
FORCEPROP 1 LASTPIN (300 525) $PN 2
J 0
(310 505);
DISPLAY 0.617021 (310 505);
PAINT ORANGE (310 505);
FORCEPROP 1 LAST LOCATION C2R6
J 0
(125 675);
DISPLAY 0.617021 (125 675);
PAINT AQUA (125 675);
FORCEPROP 1 LAST MATERIAL EMPTY
J 0
(350 525);
DISPLAY 0.617021 (350 525);
PAINT RED (350 525);
FORCEPROP 1 LAST PART_NUMBER A36096-049
J 0
(350 475);
DISPLAY 0.617021 (350 475);
PAINT BLUE (350 475);
FORCEPROP 1 LAST PACK_TYPE 0402LF
J 0
(350 425);
DISPLAY 0.617021 (350 425);
PAINT SKYBLUE (350 425);
FORCEPROP 1 LAST TOLERANCE 10%
J 0
(350 575);
DISPLAY 0.617021 (350 575);
PAINT SKYBLUE (350 575);
FORCEPROP 1 LAST PATH I40
J 0
(350 775);
DISPLAY 0.978723 (350 775);
PAINT WHITE (350 775);
DISPLAY INVISIBLE (350 775);
FORCEPROP 0 LAST CDS_SEC 1
J 0
(350 725);
PAINT MONO (350 725);
DISPLAY INVISIBLE (350 725);
FORCEPROP 2 LAST CDS_LOCATION C2R6
J 0
(125 675);
DISPLAY 0.617021 (125 675);
PAINT AQUA (125 675);
DISPLAY INVISIBLE (125 675);
FORCEPROP 2 LAST CDS_LIB mstr_discrete
J 0
(300 625);
PAINT ORANGE (300 625);
DISPLAY INVISIBLE (300 625);
FORCEPROP 2 LAST SEC 1
J 0
(350 825);
DISPLAY 0.680851 (350 825);
PAINT MONO (350 825);
DISPLAY INVISIBLE (350 825);
FORCEPROP 2 LAST SEC_TYPE 0402LF
J 0
(350 825);
DISPLAY 1.021277 (350 825);
PAINT ORANGE (350 825);
DISPLAY INVISIBLE (350 825);
FORCEPROP 0 LAST ROOM IO_SLOT
J 0
(350 825);
DISPLAY 1.021277 (350 825);
PAINT ORANGE (350 825);
DISPLAY INVISIBLE (350 825);
FORCEADD OFFPAGE..1
(0 875);
FORCEPROP 2 LAST $XR0 191 
J 0
(-252 875);
DISPLAY 0.638298 (-252 875);
PAINT MONO (-252 875);
FORCEPROP 2 LAST PATH I41
J 0
(-250 925);
DISPLAY 1.021277 (-250 925);
PAINT ORANGE (-250 925);
DISPLAY INVISIBLE (-250 925);
FORCEPROP 2 LAST CDS_LIB mstr_standard
J 0
(0 875);
PAINT ORANGE (0 875);
DISPLAY INVISIBLE (0 875);
FORCEPROP 1 LAST OFFPAGE TRUE
J 0
(325 750);
DISPLAY 0.872340 (325 750);
PAINT GREEN (325 750);
DISPLAY INVISIBLE (325 750);
FORCEPROP 1 LAST COMMENT_BODY TRUE
J 0
(125 775);
DISPLAY 0.872340 (125 775);
PAINT GREEN (125 775);
DISPLAY INVISIBLE (125 775);
FORCEADD NPN..1
(650 1550);
FORCEPROP 1 LASTPIN (700 1450) $PN 2
J 0
(725 1400);
DISPLAY 0.617021 (725 1400);
PAINT GREEN (725 1400);
FORCEPROP 1 LASTPIN (700 1650) $PN 3
J 0
(719 1660);
DISPLAY 0.617021 (719 1660);
PAINT GREEN (719 1660);
FORCEPROP 1 LAST PACK_TYPE SM
J 0
(800 1450);
DISPLAY 0.617021 (800 1450);
PAINT SKYBLUE (800 1450);
FORCEPROP 1 LAST MATERIAL IC
J 0
(800 1500);
DISPLAY 0.617021 (800 1500);
PAINT SKYBLUE (800 1500);
FORCEPROP 1 LASTPIN (550 1550) $PN 1
J 0
(495 1575);
DISPLAY 0.617021 (495 1575);
PAINT GREEN (495 1575);
FORCEPROP 1 LAST VALUE MMBT3904
J 0
(800 1550);
DISPLAY 0.617021 (800 1550);
PAINT SKYBLUE (800 1550);
FORCEPROP 1 LAST PART_NUMBER C52245-001
J 0
(800 1400);
DISPLAY 0.617021 (800 1400);
PAINT BLUE (800 1400);
FORCEPROP 1 LAST LOCATION Q9T1
J 0
(800 1600);
DISPLAY 0.617021 (800 1600);
PAINT AQUA (800 1600);
FORCEPROP 1 LAST PATH I42
J 0
(800 1650);
DISPLAY 0.978723 (800 1650);
PAINT BLUE (800 1650);
DISPLAY INVISIBLE (800 1650);
FORCEPROP 0 LAST CDS_SEC 1
J 0
(800 1650);
PAINT MONO (800 1650);
DISPLAY INVISIBLE (800 1650);
FORCEPROP 2 LAST CDS_LIB mstr_discrete
J 0
(650 1550);
PAINT ORANGE (650 1550);
DISPLAY INVISIBLE (650 1550);
FORCEPROP 2 LAST CDS_LOCATION Q9T1
J 0
(800 1600);
DISPLAY 0.617021 (800 1600);
PAINT AQUA (800 1600);
DISPLAY INVISIBLE (800 1600);
FORCEPROP 2 LAST SEC 1
J 0
(800 1700);
DISPLAY 0.680851 (800 1700);
PAINT MONO (800 1700);
DISPLAY INVISIBLE (800 1700);
FORCEPROP 2 LAST SEC_TYPE SM
J 0
(800 1700);
DISPLAY 1.021277 (800 1700);
PAINT ORANGE (800 1700);
DISPLAY INVISIBLE (800 1700);
FORCEPROP 2 LAST ROOM SB
J 0
(800 1650);
DISPLAY 1.404255 (800 1650);
PAINT ORANGE (800 1650);
DISPLAY INVISIBLE (800 1650);
FORCEADD GND..1
(-750 2400);
FORCEPROP 3 LASTPIN (-750 2450) SIG_NAME GND\g
J 0
(-740 2460);
DISPLAY 0.659574 (-740 2460);
PAINT MONO (-740 2460);
DISPLAY INVISIBLE (-740 2460);
FORCEPROP 1 LAST SIZE 1B
J 0
(-675 2350);
DISPLAY 0.872340 (-675 2350);
PAINT GREEN (-675 2350);
DISPLAY INVISIBLE (-675 2350);
FORCEPROP 1 LAST VOLTAGE 0
J 0
(-750 2400);
PAINT SKYBLUE (-750 2400);
DISPLAY INVISIBLE (-750 2400);
FORCEPROP 2 LAST CDS_LIB mstr_symbols
J 0
(-750 2400);
PAINT ORANGE (-750 2400);
DISPLAY INVISIBLE (-750 2400);
FORCEPROP 2 LAST ROOM P2V5_LAN_AUX_VR
J 0
(-1050 2475);
DISPLAY 0.617021 (-1050 2475);
PAINT ORANGE (-1050 2475);
DISPLAY INVISIBLE (-1050 2475);
FORCEPROP 2 LAST BOM_COST NT_BASE_VRD
J 0
(-1050 2475);
DISPLAY 0.617021 (-1050 2475);
PAINT ORANGE (-1050 2475);
DISPLAY INVISIBLE (-1050 2475);
FORCEPROP 1 LAST PATH I43
J 0
(-675 2400);
DISPLAY 0.872340 (-675 2400);
PAINT AQUA (-675 2400);
DISPLAY INVISIBLE (-675 2400);
FORCEPROP 1 LAST BODY_TYPE PLUMBING
J 0
(-795 2357);
DISPLAY 0.340426 (-795 2357);
PAINT GREEN (-795 2357);
DISPLAY INVISIBLE (-795 2357);
FORCEPROP 1 LAST HDL_POWER GND
J 0
(-750 2550);
DISPLAY 0.872340 (-750 2550);
PAINT GREEN (-750 2550);
DISPLAY INVISIBLE (-750 2550);
FORCEADD TAP..1
R 2
(-1250 3300);
FORCEPROP 3 LASTPIN (-1200 3300) SIG_NAME P3E_CPU1_PE3_MP_RXN<7>
J 0
(-1190 3310);
DISPLAY 0.659574 (-1190 3310);
PAINT MONO (-1190 3310);
DISPLAY INVISIBLE (-1190 3310);
FORCEPROP 1 LASTPIN (-1200 3300) BN 7
J 2
(-1188 3308);
DISPLAY 0.617021 (-1188 3308);
PAINT GREEN (-1188 3308);
FORCEPROP 1 LAST PATH I44
J 2
(-1248 3300);
DISPLAY 0.872340 (-1248 3300);
PAINT GREEN (-1248 3300);
DISPLAY INVISIBLE (-1248 3300);
FORCEPROP 2 LAST CDS_LIB mstr_standard
J 0
(-1250 3300);
PAINT MONO (-1250 3300);
DISPLAY INVISIBLE (-1250 3300);
FORCEPROP 1 LAST BODY_TYPE PLUMBING
J 2
(-1250 3350);
DISPLAY 1.446809 (-1250 3350);
PAINT GREEN (-1250 3350);
DISPLAY INVISIBLE (-1250 3350);
FORCEPROP 1 LAST HDL_TAP TRUE
J 2
(-1575 3175);
DISPLAY 1.446809 (-1575 3175);
PAINT GREEN (-1575 3175);
DISPLAY INVISIBLE (-1575 3175);
FORCEADD TAP..1
R 2
(-1000 3250);
FORCEPROP 3 LASTPIN (-950 3250) SIG_NAME P3E_CPU1_PE3_MP_RXP<7>
J 0
(-940 3260);
DISPLAY 0.659574 (-940 3260);
PAINT MONO (-940 3260);
DISPLAY INVISIBLE (-940 3260);
FORCEPROP 1 LASTPIN (-950 3250) BN 7
J 2
(-938 3258);
DISPLAY 0.617021 (-938 3258);
PAINT GREEN (-938 3258);
FORCEPROP 1 LAST PATH I45
J 2
(-998 3250);
DISPLAY 0.872340 (-998 3250);
PAINT GREEN (-998 3250);
DISPLAY INVISIBLE (-998 3250);
FORCEPROP 2 LAST CDS_LIB mstr_standard
J 0
(-1000 3250);
PAINT MONO (-1000 3250);
DISPLAY INVISIBLE (-1000 3250);
FORCEPROP 1 LAST BODY_TYPE PLUMBING
J 2
(-1000 3300);
DISPLAY 1.446809 (-1000 3300);
PAINT GREEN (-1000 3300);
DISPLAY INVISIBLE (-1000 3300);
FORCEPROP 1 LAST HDL_TAP TRUE
J 2
(-1325 3125);
DISPLAY 1.446809 (-1325 3125);
PAINT GREEN (-1325 3125);
DISPLAY INVISIBLE (-1325 3125);
FORCEADD TAP..1
R 2
(-1250 3400);
FORCEPROP 3 LASTPIN (-1200 3400) SIG_NAME P3E_CPU1_PE3_MP_RXN<6>
J 0
(-1190 3410);
DISPLAY 0.659574 (-1190 3410);
PAINT MONO (-1190 3410);
DISPLAY INVISIBLE (-1190 3410);
FORCEPROP 1 LASTPIN (-1200 3400) BN 6
J 2
(-1188 3408);
DISPLAY 0.617021 (-1188 3408);
PAINT GREEN (-1188 3408);
FORCEPROP 1 LAST PATH I46
J 2
(-1248 3400);
DISPLAY 0.872340 (-1248 3400);
PAINT GREEN (-1248 3400);
DISPLAY INVISIBLE (-1248 3400);
FORCEPROP 2 LAST CDS_LIB mstr_standard
J 0
(-1250 3400);
PAINT MONO (-1250 3400);
DISPLAY INVISIBLE (-1250 3400);
FORCEPROP 1 LAST BODY_TYPE PLUMBING
J 2
(-1250 3450);
DISPLAY 1.446809 (-1250 3450);
PAINT GREEN (-1250 3450);
DISPLAY INVISIBLE (-1250 3450);
FORCEPROP 1 LAST HDL_TAP TRUE
J 2
(-1575 3275);
DISPLAY 1.446809 (-1575 3275);
PAINT GREEN (-1575 3275);
DISPLAY INVISIBLE (-1575 3275);
FORCEADD TAP..1
R 2
(-1250 3600);
FORCEPROP 3 LASTPIN (-1200 3600) SIG_NAME P3E_CPU1_PE3_MP_RXN<5>
J 0
(-1190 3610);
DISPLAY 0.659574 (-1190 3610);
PAINT MONO (-1190 3610);
DISPLAY INVISIBLE (-1190 3610);
FORCEPROP 1 LASTPIN (-1200 3600) BN 5
J 2
(-1188 3608);
DISPLAY 0.617021 (-1188 3608);
PAINT GREEN (-1188 3608);
FORCEPROP 1 LAST PATH I47
J 2
(-1248 3600);
DISPLAY 0.872340 (-1248 3600);
PAINT GREEN (-1248 3600);
DISPLAY INVISIBLE (-1248 3600);
FORCEPROP 2 LAST CDS_LIB mstr_standard
J 0
(-1250 3600);
PAINT ORANGE (-1250 3600);
DISPLAY INVISIBLE (-1250 3600);
FORCEPROP 1 LAST BODY_TYPE PLUMBING
J 2
(-1250 3650);
DISPLAY 1.446809 (-1250 3650);
PAINT GREEN (-1250 3650);
DISPLAY INVISIBLE (-1250 3650);
FORCEPROP 1 LAST HDL_TAP TRUE
J 2
(-1575 3475);
DISPLAY 1.446809 (-1575 3475);
PAINT GREEN (-1575 3475);
DISPLAY INVISIBLE (-1575 3475);
FORCEADD TAP..1
R 2
(-1000 3450);
FORCEPROP 3 LASTPIN (-950 3450) SIG_NAME P3E_CPU1_PE3_MP_RXP<6>
J 0
(-940 3460);
DISPLAY 0.659574 (-940 3460);
PAINT MONO (-940 3460);
DISPLAY INVISIBLE (-940 3460);
FORCEPROP 1 LASTPIN (-950 3450) BN 6
J 2
(-938 3458);
DISPLAY 0.617021 (-938 3458);
PAINT GREEN (-938 3458);
FORCEPROP 1 LAST PATH I48
J 2
(-998 3450);
DISPLAY 0.872340 (-998 3450);
PAINT GREEN (-998 3450);
DISPLAY INVISIBLE (-998 3450);
FORCEPROP 2 LAST CDS_LIB mstr_standard
J 0
(-1000 3450);
PAINT MONO (-1000 3450);
DISPLAY INVISIBLE (-1000 3450);
FORCEPROP 1 LAST BODY_TYPE PLUMBING
J 2
(-1000 3500);
DISPLAY 1.446809 (-1000 3500);
PAINT GREEN (-1000 3500);
DISPLAY INVISIBLE (-1000 3500);
FORCEPROP 1 LAST HDL_TAP TRUE
J 2
(-1325 3325);
DISPLAY 1.446809 (-1325 3325);
PAINT GREEN (-1325 3325);
DISPLAY INVISIBLE (-1325 3325);
FORCEADD TAP..1
R 2
(-1000 3650);
FORCEPROP 3 LASTPIN (-950 3650) SIG_NAME P3E_CPU1_PE3_MP_RXP<5>
J 0
(-940 3660);
DISPLAY 0.659574 (-940 3660);
PAINT MONO (-940 3660);
DISPLAY INVISIBLE (-940 3660);
FORCEPROP 1 LASTPIN (-950 3650) BN 5
J 2
(-938 3658);
DISPLAY 0.617021 (-938 3658);
PAINT GREEN (-938 3658);
FORCEPROP 1 LAST PATH I49
J 2
(-998 3650);
DISPLAY 0.872340 (-998 3650);
PAINT GREEN (-998 3650);
DISPLAY INVISIBLE (-998 3650);
FORCEPROP 2 LAST CDS_LIB mstr_standard
J 0
(-1000 3650);
PAINT ORANGE (-1000 3650);
DISPLAY INVISIBLE (-1000 3650);
FORCEPROP 1 LAST BODY_TYPE PLUMBING
J 2
(-1000 3700);
DISPLAY 1.446809 (-1000 3700);
PAINT GREEN (-1000 3700);
DISPLAY INVISIBLE (-1000 3700);
FORCEPROP 1 LAST HDL_TAP TRUE
J 2
(-1325 3525);
DISPLAY 1.446809 (-1325 3525);
PAINT GREEN (-1325 3525);
DISPLAY INVISIBLE (-1325 3525);
FORCEADD DIODE..1
(-1550 1550);
FORCEPROP 1 LAST MATERIAL IC
J 0
(-1650 1397);
DISPLAY 0.617021 (-1650 1397);
PAINT SKYBLUE (-1650 1397);
FORCEPROP 1 LAST PART_NUMBER H71799-001
J 0
(-1650 1650);
DISPLAY 0.617021 (-1650 1650);
PAINT BLUE (-1650 1650);
FORCEPROP 1 LAST VALUE SDMK0340L
J 0
(-1650 1450);
DISPLAY 0.617021 (-1650 1450);
PAINT SKYBLUE (-1650 1450);
FORCEPROP 1 LAST LOCATION CR1F4
J 0
(-1652 1706);
DISPLAY 0.617021 (-1652 1706);
PAINT AQUA (-1652 1706);
FORCEPROP 1 LAST PACK_TYPE SM
J 0
(-1650 1360);
DISPLAY 0.617021 (-1650 1360);
PAINT SKYBLUE (-1650 1360);
FORCEPROP 1 LASTPIN (-1450 1550) $PN 1
J 0
(-1485 1560);
DISPLAY 0.617021 (-1485 1560);
PAINT AQUA (-1485 1560);
FORCEPROP 1 LASTPIN (-1650 1550) $PN 2
J 2
(-1615 1560);
DISPLAY 0.617021 (-1615 1560);
PAINT AQUA (-1615 1560);
FORCEPROP 2 LAST SEC 1
J 0
(-1550 1825);
DISPLAY 0.680851 (-1550 1825);
PAINT MONO (-1550 1825);
DISPLAY INVISIBLE (-1550 1825);
FORCEPROP 2 LAST SEC_TYPE SM
J 0
(-1550 1825);
DISPLAY 1.021277 (-1550 1825);
PAINT ORANGE (-1550 1825);
DISPLAY INVISIBLE (-1550 1825);
FORCEPROP 0 LAST BOM_COST IO_SLOT
J 0
(-1575 1900);
DISPLAY 1.021277 (-1575 1900);
PAINT ORANGE (-1575 1900);
DISPLAY INVISIBLE (-1575 1900);
FORCEPROP 0 LAST ROOM IO_SLOT
J 0
(-1575 1800);
DISPLAY 1.021277 (-1575 1800);
PAINT ORANGE (-1575 1800);
DISPLAY INVISIBLE (-1575 1800);
FORCEPROP 2 LAST CDS_LIB mstr_discrete
J 0
(-1550 1550);
PAINT ORANGE (-1550 1550);
DISPLAY INVISIBLE (-1550 1550);
FORCEPROP 2 LAST CDS_LOCATION CR1F4
J 0
(-1577 1706);
DISPLAY 0.617021 (-1577 1706);
PAINT AQUA (-1577 1706);
DISPLAY INVISIBLE (-1577 1706);
FORCEPROP 0 LAST CDS_SEC 1
J 0
(-1575 1750);
PAINT MONO (-1575 1750);
DISPLAY INVISIBLE (-1575 1750);
FORCEPROP 1 LAST PATH I5
J 0
(-1570 1760);
DISPLAY 0.978723 (-1570 1760);
PAINT PINK (-1570 1760);
DISPLAY INVISIBLE (-1570 1760);
FORCEADD TAP..1
R 2
(-1000 3750);
FORCEPROP 3 LASTPIN (-950 3750) SIG_NAME P3E_CPU1_PE3_MP_RXP<4>
J 0
(-940 3760);
DISPLAY 0.659574 (-940 3760);
PAINT MONO (-940 3760);
DISPLAY INVISIBLE (-940 3760);
FORCEPROP 1 LASTPIN (-950 3750) BN 4
J 2
(-938 3758);
DISPLAY 0.617021 (-938 3758);
PAINT GREEN (-938 3758);
FORCEPROP 1 LAST PATH I50
J 2
(-998 3750);
DISPLAY 0.872340 (-998 3750);
PAINT GREEN (-998 3750);
DISPLAY INVISIBLE (-998 3750);
FORCEPROP 2 LAST CDS_LIB mstr_standard
J 0
(-1000 3750);
PAINT MONO (-1000 3750);
DISPLAY INVISIBLE (-1000 3750);
FORCEPROP 1 LAST BODY_TYPE PLUMBING
J 2
(-1000 3800);
DISPLAY 1.446809 (-1000 3800);
PAINT GREEN (-1000 3800);
DISPLAY INVISIBLE (-1000 3800);
FORCEPROP 1 LAST HDL_TAP TRUE
J 2
(-1325 3625);
DISPLAY 1.446809 (-1325 3625);
PAINT GREEN (-1325 3625);
DISPLAY INVISIBLE (-1325 3625);
FORCEADD OFFPAGE..5
(-2875 4825);
FORCEPROP 2 LAST $XR0 66 
J 0
(-3129 4825);
DISPLAY 0.638298 (-3129 4825);
PAINT MONO (-3129 4825);
FORCEPROP 2 LAST PATH I51
J 0
(-3125 4875);
DISPLAY 1.021277 (-3125 4875);
PAINT ORANGE (-3125 4875);
DISPLAY INVISIBLE (-3125 4875);
FORCEPROP 2 LAST CDS_LIB mstr_standard
J 0
(-2875 4825);
PAINT ORANGE (-2875 4825);
DISPLAY INVISIBLE (-2875 4825);
FORCEPROP 1 LAST OFFPAGE TRUE
J 0
(-2550 4700);
DISPLAY 0.872340 (-2550 4700);
PAINT GREEN (-2550 4700);
DISPLAY INVISIBLE (-2550 4700);
FORCEPROP 1 LAST COMMENT_BODY TRUE
J 0
(-2775 4750);
DISPLAY 0.872340 (-2775 4750);
PAINT GREEN (-2775 4750);
DISPLAY INVISIBLE (-2775 4750);
FORCEADD TAP..1
R 2
(-1250 3950);
FORCEPROP 3 LASTPIN (-1200 3950) SIG_NAME P3E_CPU1_PE3_MP_RXN<3>
J 0
(-1190 3960);
DISPLAY 0.659574 (-1190 3960);
PAINT MONO (-1190 3960);
DISPLAY INVISIBLE (-1190 3960);
FORCEPROP 1 LASTPIN (-1200 3950) BN 3
J 2
(-1188 3958);
DISPLAY 0.617021 (-1188 3958);
PAINT GREEN (-1188 3958);
FORCEPROP 1 LAST PATH I52
J 2
(-1248 3950);
DISPLAY 0.872340 (-1248 3950);
PAINT GREEN (-1248 3950);
DISPLAY INVISIBLE (-1248 3950);
FORCEPROP 2 LAST CDS_LIB mstr_standard
J 0
(-1250 3950);
PAINT MONO (-1250 3950);
DISPLAY INVISIBLE (-1250 3950);
FORCEPROP 1 LAST BODY_TYPE PLUMBING
J 2
(-1250 4000);
DISPLAY 1.446809 (-1250 4000);
PAINT GREEN (-1250 4000);
DISPLAY INVISIBLE (-1250 4000);
FORCEPROP 1 LAST HDL_TAP TRUE
J 2
(-1575 3825);
DISPLAY 1.446809 (-1575 3825);
PAINT GREEN (-1575 3825);
DISPLAY INVISIBLE (-1575 3825);
FORCEADD TAP..1
R 2
(-1250 4150);
FORCEPROP 3 LASTPIN (-1200 4150) SIG_NAME P3E_CPU1_PE3_MP_RXN<2>
J 0
(-1190 4160);
DISPLAY 0.659574 (-1190 4160);
PAINT MONO (-1190 4160);
DISPLAY INVISIBLE (-1190 4160);
FORCEPROP 1 LASTPIN (-1200 4150) BN 2
J 2
(-1188 4158);
DISPLAY 0.617021 (-1188 4158);
PAINT GREEN (-1188 4158);
FORCEPROP 1 LAST PATH I53
J 2
(-1248 4150);
DISPLAY 0.872340 (-1248 4150);
PAINT GREEN (-1248 4150);
DISPLAY INVISIBLE (-1248 4150);
FORCEPROP 2 LAST CDS_LIB mstr_standard
J 0
(-1250 4150);
PAINT ORANGE (-1250 4150);
DISPLAY INVISIBLE (-1250 4150);
FORCEPROP 1 LAST BODY_TYPE PLUMBING
J 2
(-1250 4200);
DISPLAY 1.446809 (-1250 4200);
PAINT GREEN (-1250 4200);
DISPLAY INVISIBLE (-1250 4200);
FORCEPROP 1 LAST HDL_TAP TRUE
J 2
(-1575 4025);
DISPLAY 1.446809 (-1575 4025);
PAINT GREEN (-1575 4025);
DISPLAY INVISIBLE (-1575 4025);
FORCEADD TAP..1
R 2
(-1250 4350);
FORCEPROP 3 LASTPIN (-1200 4350) SIG_NAME P3E_CPU1_PE3_MP_RXN<1>
J 0
(-1190 4360);
DISPLAY 0.659574 (-1190 4360);
PAINT MONO (-1190 4360);
DISPLAY INVISIBLE (-1190 4360);
FORCEPROP 1 LASTPIN (-1200 4350) BN 1
J 2
(-1188 4358);
DISPLAY 0.617021 (-1188 4358);
PAINT GREEN (-1188 4358);
FORCEPROP 1 LAST PATH I54
J 2
(-1248 4350);
DISPLAY 0.872340 (-1248 4350);
PAINT GREEN (-1248 4350);
DISPLAY INVISIBLE (-1248 4350);
FORCEPROP 2 LAST CDS_LIB mstr_standard
J 0
(-1250 4350);
PAINT MONO (-1250 4350);
DISPLAY INVISIBLE (-1250 4350);
FORCEPROP 1 LAST BODY_TYPE PLUMBING
J 2
(-1250 4400);
DISPLAY 1.446809 (-1250 4400);
PAINT GREEN (-1250 4400);
DISPLAY INVISIBLE (-1250 4400);
FORCEPROP 1 LAST HDL_TAP TRUE
J 2
(-1575 4225);
DISPLAY 1.446809 (-1575 4225);
PAINT GREEN (-1575 4225);
DISPLAY INVISIBLE (-1575 4225);
FORCEADD TAP..1
R 2
(-1000 3900);
FORCEPROP 3 LASTPIN (-950 3900) SIG_NAME P3E_CPU1_PE3_MP_RXP<3>
J 0
(-940 3910);
DISPLAY 0.659574 (-940 3910);
PAINT MONO (-940 3910);
DISPLAY INVISIBLE (-940 3910);
FORCEPROP 1 LASTPIN (-950 3900) BN 3
J 2
(-938 3908);
DISPLAY 0.617021 (-938 3908);
PAINT GREEN (-938 3908);
FORCEPROP 1 LAST PATH I55
J 2
(-998 3900);
DISPLAY 0.872340 (-998 3900);
PAINT GREEN (-998 3900);
DISPLAY INVISIBLE (-998 3900);
FORCEPROP 2 LAST CDS_LIB mstr_standard
J 0
(-1000 3900);
PAINT MONO (-1000 3900);
DISPLAY INVISIBLE (-1000 3900);
FORCEPROP 1 LAST BODY_TYPE PLUMBING
J 2
(-1000 3950);
DISPLAY 1.446809 (-1000 3950);
PAINT GREEN (-1000 3950);
DISPLAY INVISIBLE (-1000 3950);
FORCEPROP 1 LAST HDL_TAP TRUE
J 2
(-1325 3775);
DISPLAY 1.446809 (-1325 3775);
PAINT GREEN (-1325 3775);
DISPLAY INVISIBLE (-1325 3775);
FORCEADD TAP..1
R 2
(-1000 4200);
FORCEPROP 3 LASTPIN (-950 4200) SIG_NAME P3E_CPU1_PE3_MP_RXP<2>
J 0
(-940 4210);
DISPLAY 0.659574 (-940 4210);
PAINT MONO (-940 4210);
DISPLAY INVISIBLE (-940 4210);
FORCEPROP 1 LASTPIN (-950 4200) BN 2
J 2
(-938 4208);
DISPLAY 0.617021 (-938 4208);
PAINT GREEN (-938 4208);
FORCEPROP 1 LAST PATH I56
J 2
(-998 4200);
DISPLAY 0.872340 (-998 4200);
PAINT GREEN (-998 4200);
DISPLAY INVISIBLE (-998 4200);
FORCEPROP 2 LAST CDS_LIB mstr_standard
J 0
(-1000 4200);
PAINT ORANGE (-1000 4200);
DISPLAY INVISIBLE (-1000 4200);
FORCEPROP 1 LAST BODY_TYPE PLUMBING
J 2
(-1000 4250);
DISPLAY 1.446809 (-1000 4250);
PAINT GREEN (-1000 4250);
DISPLAY INVISIBLE (-1000 4250);
FORCEPROP 1 LAST HDL_TAP TRUE
J 2
(-1325 4075);
DISPLAY 1.446809 (-1325 4075);
PAINT GREEN (-1325 4075);
DISPLAY INVISIBLE (-1325 4075);
FORCEADD TAP..1
R 2
(-1000 4300);
FORCEPROP 3 LASTPIN (-950 4300) SIG_NAME P3E_CPU1_PE3_MP_RXP<1>
J 0
(-940 4310);
DISPLAY 0.659574 (-940 4310);
PAINT MONO (-940 4310);
DISPLAY INVISIBLE (-940 4310);
FORCEPROP 1 LASTPIN (-950 4300) BN 1
J 2
(-938 4308);
DISPLAY 0.617021 (-938 4308);
PAINT GREEN (-938 4308);
FORCEPROP 1 LAST PATH I57
J 2
(-998 4300);
DISPLAY 0.872340 (-998 4300);
PAINT GREEN (-998 4300);
DISPLAY INVISIBLE (-998 4300);
FORCEPROP 2 LAST CDS_LIB mstr_standard
J 0
(-1000 4300);
PAINT MONO (-1000 4300);
DISPLAY INVISIBLE (-1000 4300);
FORCEPROP 1 LAST BODY_TYPE PLUMBING
J 2
(-1000 4350);
DISPLAY 1.446809 (-1000 4350);
PAINT GREEN (-1000 4350);
DISPLAY INVISIBLE (-1000 4350);
FORCEPROP 1 LAST HDL_TAP TRUE
J 2
(-1325 4175);
DISPLAY 1.446809 (-1325 4175);
PAINT GREEN (-1325 4175);
DISPLAY INVISIBLE (-1325 4175);
FORCEADD TAP..1
R 2
(-1250 4500);
FORCEPROP 3 LASTPIN (-1200 4500) SIG_NAME P3E_CPU1_PE3_MP_RXN<0>
J 0
(-1190 4510);
DISPLAY 0.659574 (-1190 4510);
PAINT MONO (-1190 4510);
DISPLAY INVISIBLE (-1190 4510);
FORCEPROP 1 LASTPIN (-1200 4500) BN 0
J 2
(-1188 4508);
DISPLAY 0.617021 (-1188 4508);
PAINT GREEN (-1188 4508);
FORCEPROP 1 LAST PATH I58
J 2
(-1248 4500);
DISPLAY 0.872340 (-1248 4500);
PAINT GREEN (-1248 4500);
DISPLAY INVISIBLE (-1248 4500);
FORCEPROP 2 LAST CDS_LIB mstr_standard
J 0
(-1250 4500);
PAINT MONO (-1250 4500);
DISPLAY INVISIBLE (-1250 4500);
FORCEPROP 1 LAST BODY_TYPE PLUMBING
J 2
(-1250 4550);
DISPLAY 1.446809 (-1250 4550);
PAINT GREEN (-1250 4550);
DISPLAY INVISIBLE (-1250 4550);
FORCEPROP 1 LAST HDL_TAP TRUE
J 2
(-1575 4375);
DISPLAY 1.446809 (-1575 4375);
PAINT GREEN (-1575 4375);
DISPLAY INVISIBLE (-1575 4375);
FORCEADD TAP..1
R 2
(-1000 4450);
FORCEPROP 3 LASTPIN (-950 4450) SIG_NAME P3E_CPU1_PE3_MP_RXP<0>
J 0
(-940 4460);
DISPLAY 0.659574 (-940 4460);
PAINT MONO (-940 4460);
DISPLAY INVISIBLE (-940 4460);
FORCEPROP 1 LASTPIN (-950 4450) BN 0
J 2
(-938 4458);
DISPLAY 0.617021 (-938 4458);
PAINT GREEN (-938 4458);
FORCEPROP 1 LAST PATH I59
J 2
(-998 4450);
DISPLAY 0.872340 (-998 4450);
PAINT GREEN (-998 4450);
DISPLAY INVISIBLE (-998 4450);
FORCEPROP 2 LAST CDS_LIB mstr_standard
J 0
(-1000 4450);
PAINT MONO (-1000 4450);
DISPLAY INVISIBLE (-1000 4450);
FORCEPROP 1 LAST BODY_TYPE PLUMBING
J 2
(-1000 4500);
DISPLAY 1.446809 (-1000 4500);
PAINT GREEN (-1000 4500);
DISPLAY INVISIBLE (-1000 4500);
FORCEPROP 1 LAST HDL_TAP TRUE
J 2
(-1325 4325);
DISPLAY 1.446809 (-1325 4325);
PAINT GREEN (-1325 4325);
DISPLAY INVISIBLE (-1325 4325);
FORCEADD OFFPAGE..1
(-2875 2175);
FORCEPROP 2 LAST $XR0 182 
J 0
(-3157 2175);
DISPLAY 0.638298 (-3157 2175);
PAINT MONO (-3157 2175);
FORCEPROP 2 LAST PATH I6
J 0
(-3150 2225);
DISPLAY 1.021277 (-3150 2225);
PAINT ORANGE (-3150 2225);
DISPLAY INVISIBLE (-3150 2225);
FORCEPROP 2 LAST CDS_LIB mstr_standard
J 0
(-2875 2175);
PAINT ORANGE (-2875 2175);
DISPLAY INVISIBLE (-2875 2175);
FORCEPROP 1 LAST OFFPAGE TRUE
J 0
(-2550 2050);
DISPLAY 0.872340 (-2550 2050);
PAINT GREEN (-2550 2050);
DISPLAY INVISIBLE (-2550 2050);
FORCEPROP 1 LAST COMMENT_BODY TRUE
J 0
(-2750 2075);
DISPLAY 0.872340 (-2750 2075);
PAINT GREEN (-2750 2075);
DISPLAY INVISIBLE (-2750 2075);
FORCEADD TTL08..1
(850 825);
FORCEPROP 1 LAST MATERIAL IC
J 0
(750 1000);
DISPLAY 0.617021 (750 1000);
PAINT SKYBLUE (750 1000);
FORCEPROP 2 LASTPIN (700 875) $PN 9
J 2
(690 885);
DISPLAY 0.617021 (690 885);
PAINT ORANGE (690 885);
FORCEPROP 2 LASTPIN (700 775) $PN 10
J 2
(690 785);
DISPLAY 0.617021 (690 785);
PAINT ORANGE (690 785);
FORCEPROP 2 LASTPIN (1000 825) $PN 8
J 0
(1010 835);
DISPLAY 0.617021 (1010 835);
PAINT ORANGE (1010 835);
FORCEPROP 1 LAST LOCATION U8E1
J 0
(750 1050);
DISPLAY 0.617021 (750 1050);
PAINT AQUA (750 1050);
FORCEPROP 1 LAST VALUE 74LVC08A
J 0
(750 950);
DISPLAY 0.617021 (750 950);
PAINT SKYBLUE (750 950);
FORCEPROP 1 LAST POWER_GROUP VCC=P3V3_STBY;GND=GND;TH=GND
J 0
(750 625);
DISPLAY 0.617021 (750 625);
PAINT ORANGE (750 625);
FORCEPROP 1 LAST PART_NUMBER D90404-001
J 0
(750 675);
DISPLAY 0.617021 (750 675);
PAINT BLUE (750 675);
FORCEPROP 1 LAST PATH I60
J 0
(1225 1000);
DISPLAY 0.978723 (1225 1000);
PAINT BLUE (1225 1000);
DISPLAY INVISIBLE (1225 1000);
FORCEPROP 0 LAST CDS_SEC 2
J 0
(750 1100);
PAINT MONO (750 1100);
DISPLAY INVISIBLE (750 1100);
FORCEPROP 2 LAST CDS_LIB mstr_ttl
J 0
(850 825);
PAINT MONO (850 825);
DISPLAY INVISIBLE (850 825);
FORCEPROP 2 LAST SEC 2
J 0
(750 1100);
DISPLAY 0.680851 (750 1100);
PAINT MONO (750 1100);
DISPLAY INVISIBLE (750 1100);
FORCEPROP 2 LAST BOM_COST FAST_PROCHOT
J 0
(750 1150);
DISPLAY 1.021277 (750 1150);
PAINT ORANGE (750 1150);
DISPLAY INVISIBLE (750 1150);
FORCEPROP 2 LAST SEC_TYPE QFN15
J 0
(750 1100);
DISPLAY 1.021277 (750 1100);
PAINT ORANGE (750 1100);
DISPLAY INVISIBLE (750 1100);
FORCEPROP 2 LAST CDS_LOCATION U8E1
J 0
(750 1050);
DISPLAY 0.617021 (750 1050);
PAINT AQUA (750 1050);
DISPLAY INVISIBLE (750 1050);
FORCEPROP 2 LAST ROOM FAST_PROCHOT
J 0
(750 1100);
DISPLAY 1.021277 (750 1100);
PAINT ORANGE (750 1100);
DISPLAY INVISIBLE (750 1100);
FORCEPROP 1 LAST PACK_TYPE QFN15
J 0
(750 1100);
DISPLAY 0.978723 (750 1100);
PAINT SKYBLUE (750 1100);
DISPLAY INVISIBLE (750 1100);
FORCEADD GND..1
(700 1275);
FORCEPROP 3 LASTPIN (700 1325) SIG_NAME GND\g
J 0
(710 1335);
DISPLAY 0.659574 (710 1335);
PAINT MONO (710 1335);
DISPLAY INVISIBLE (710 1335);
FORCEPROP 1 LAST PATH I61
J 0
(775 1275);
DISPLAY 0.872340 (775 1275);
PAINT AQUA (775 1275);
DISPLAY INVISIBLE (775 1275);
FORCEPROP 2 LAST BOM_COST NT_BASE_VRD
J 0
(400 1350);
DISPLAY 0.617021 (400 1350);
PAINT ORANGE (400 1350);
DISPLAY INVISIBLE (400 1350);
FORCEPROP 2 LAST ROOM P2V5_LAN_AUX_VR
J 0
(400 1350);
DISPLAY 0.617021 (400 1350);
PAINT ORANGE (400 1350);
DISPLAY INVISIBLE (400 1350);
FORCEPROP 1 LAST SIZE 1B
J 0
(775 1225);
DISPLAY 0.872340 (775 1225);
PAINT GREEN (775 1225);
DISPLAY INVISIBLE (775 1225);
FORCEPROP 1 LAST VOLTAGE 0
J 0
(700 1275);
PAINT SKYBLUE (700 1275);
DISPLAY INVISIBLE (700 1275);
FORCEPROP 2 LAST CDS_LIB mstr_symbols
J 0
(700 1275);
PAINT ORANGE (700 1275);
DISPLAY INVISIBLE (700 1275);
FORCEPROP 1 LAST BODY_TYPE PLUMBING
J 0
(655 1232);
DISPLAY 0.340426 (655 1232);
PAINT GREEN (655 1232);
DISPLAY INVISIBLE (655 1232);
FORCEPROP 1 LAST HDL_POWER GND
J 0
(700 1425);
DISPLAY 0.872340 (700 1425);
PAINT GREEN (700 1425);
DISPLAY INVISIBLE (700 1425);
FORCEADD GND..1
(1150 1250);
FORCEPROP 3 LASTPIN (1150 1300) SIG_NAME GND\g
J 0
(1160 1310);
DISPLAY 0.659574 (1160 1310);
PAINT MONO (1160 1310);
DISPLAY INVISIBLE (1160 1310);
FORCEPROP 1 LAST PATH I62
J 0
(1225 1250);
DISPLAY 0.872340 (1225 1250);
PAINT AQUA (1225 1250);
DISPLAY INVISIBLE (1225 1250);
FORCEPROP 2 LAST BOM_COST NT_BASE_VRD
J 0
(850 1325);
DISPLAY 0.617021 (850 1325);
PAINT ORANGE (850 1325);
DISPLAY INVISIBLE (850 1325);
FORCEPROP 2 LAST ROOM P2V5_LAN_AUX_VR
J 0
(850 1325);
DISPLAY 0.617021 (850 1325);
PAINT ORANGE (850 1325);
DISPLAY INVISIBLE (850 1325);
FORCEPROP 1 LAST SIZE 1B
J 0
(1225 1200);
DISPLAY 0.872340 (1225 1200);
PAINT GREEN (1225 1200);
DISPLAY INVISIBLE (1225 1200);
FORCEPROP 1 LAST VOLTAGE 0
J 0
(1150 1250);
PAINT SKYBLUE (1150 1250);
DISPLAY INVISIBLE (1150 1250);
FORCEPROP 2 LAST CDS_LIB mstr_symbols
J 0
(1150 1250);
PAINT ORANGE (1150 1250);
DISPLAY INVISIBLE (1150 1250);
FORCEPROP 1 LAST BODY_TYPE PLUMBING
J 0
(1105 1207);
DISPLAY 0.340426 (1105 1207);
PAINT GREEN (1105 1207);
DISPLAY INVISIBLE (1105 1207);
FORCEPROP 1 LAST HDL_POWER GND
J 0
(1150 1400);
DISPLAY 0.872340 (1150 1400);
PAINT GREEN (1150 1400);
DISPLAY INVISIBLE (1150 1400);
FORCEADD RES..1
(1650 825);
FORCEPROP 1 LAST WATTAGE 1/16W
J 2
(1625 675);
DISPLAY 0.617021 (1625 675);
PAINT SKYBLUE (1625 675);
FORCEPROP 1 LASTPIN (1750 825) $PN 2
J 0
(1712 837);
DISPLAY 0.617021 (1712 837);
PAINT ORANGE (1712 837);
FORCEPROP 1 LASTPIN (1550 825) $PN 1
J 0
(1562 837);
DISPLAY 0.617021 (1562 837);
PAINT ORANGE (1562 837);
FORCEPROP 1 LAST LOCATION R8E5
J 0
(1600 875);
DISPLAY 0.617021 (1600 875);
PAINT AQUA (1600 875);
FORCEPROP 1 LAST VALUE 33.2
J 2
(1625 725);
DISPLAY 0.617021 (1625 725);
PAINT SKYBLUE (1625 725);
FORCEPROP 1 LAST TOLERANCE 1%
J 0
(1650 725);
DISPLAY 0.617021 (1650 725);
PAINT SKYBLUE (1650 725);
FORCEPROP 1 LAST MATERIAL CHIP
J 0
(1650 675);
DISPLAY 0.617021 (1650 675);
PAINT SKYBLUE (1650 675);
FORCEPROP 1 LAST PACK_TYPE 0402
J 0
(1900 675);
DISPLAY 0.617021 (1900 675);
PAINT SKYBLUE (1900 675);
FORCEPROP 1 LAST PART_NUMBER G21796-074
J 0
(1450 600);
DISPLAY 0.617021 (1450 600);
PAINT BLUE (1450 600);
FORCEPROP 1 LAST PATH I63
J 0
(1600 975);
DISPLAY 0.978723 (1600 975);
PAINT WHITE (1600 975);
DISPLAY INVISIBLE (1600 975);
FORCEPROP 0 LAST CDS_SEC 1
J 0
(1600 925);
PAINT MONO (1600 925);
DISPLAY INVISIBLE (1600 925);
FORCEPROP 0 LAST ROOM IO_SLOT
J 0
(1600 975);
DISPLAY 1.021277 (1600 975);
PAINT ORANGE (1600 975);
DISPLAY INVISIBLE (1600 975);
FORCEPROP 2 LAST SEC_TYPE 0402
J 0
(1600 1025);
DISPLAY 1.021277 (1600 1025);
PAINT ORANGE (1600 1025);
DISPLAY INVISIBLE (1600 1025);
FORCEPROP 2 LAST SEC 1
J 0
(1600 1025);
DISPLAY 0.680851 (1600 1025);
PAINT MONO (1600 1025);
DISPLAY INVISIBLE (1600 1025);
FORCEPROP 2 LAST CDS_LOCATION R8E5
J 0
(1600 875);
DISPLAY 0.617021 (1600 875);
PAINT AQUA (1600 875);
DISPLAY INVISIBLE (1600 875);
FORCEPROP 2 LAST CDS_LIB mstr_discrete
J 0
(1650 825);
PAINT ORANGE (1650 825);
DISPLAY INVISIBLE (1650 825);
FORCEADD RES..2
(1150 1550);
FORCEPROP 1 LAST WATTAGE 1/16W
J 0
(1190 1525);
DISPLAY 0.617021 (1190 1525);
PAINT SKYBLUE (1190 1525);
FORCEPROP 1 LAST TOLERANCE 1%
J 0
(1195 1575);
DISPLAY 0.617021 (1195 1575);
PAINT SKYBLUE (1195 1575);
FORCEPROP 1 LASTPIN (1150 1650) $PN 1
J 0
(1155 1612);
DISPLAY 0.617021 (1155 1612);
PAINT ORANGE (1155 1612);
FORCEPROP 1 LAST PART_NUMBER G21796-161
J 0
(1190 1425);
DISPLAY 0.617021 (1190 1425);
PAINT BLUE (1190 1425);
FORCEPROP 1 LAST MATERIAL CHIP
J 0
(1190 1475);
DISPLAY 0.617021 (1190 1475);
PAINT SKYBLUE (1190 1475);
FORCEPROP 1 LAST PACK_TYPE 0402
J 0
(1190 1375);
DISPLAY 0.617021 (1190 1375);
PAINT SKYBLUE (1190 1375);
FORCEPROP 1 LASTPIN (1150 1450) $PN 2
J 0
(1155 1460);
DISPLAY 0.617021 (1155 1460);
PAINT ORANGE (1155 1460);
FORCEPROP 1 LAST LOCATION R9T3
J 0
(1195 1675);
DISPLAY 0.617021 (1195 1675);
PAINT AQUA (1195 1675);
FORCEPROP 1 LAST VALUE 6.19K
J 0
(1195 1625);
DISPLAY 0.617021 (1195 1625);
PAINT SKYBLUE (1195 1625);
FORCEPROP 1 LAST PATH I64
J 0
(1200 1725);
DISPLAY 0.978723 (1200 1725);
PAINT WHITE (1200 1725);
DISPLAY INVISIBLE (1200 1725);
FORCEPROP 0 LAST BOM_COST IO_SLOT
J 0
(1200 1875);
DISPLAY 1.021277 (1200 1875);
PAINT ORANGE (1200 1875);
DISPLAY INVISIBLE (1200 1875);
FORCEPROP 2 LAST SEC 1
J 0
(1200 1775);
DISPLAY 0.680851 (1200 1775);
PAINT MONO (1200 1775);
DISPLAY INVISIBLE (1200 1775);
FORCEPROP 2 LAST SEC_TYPE 0402
J 0
(1200 1775);
DISPLAY 1.021277 (1200 1775);
PAINT ORANGE (1200 1775);
DISPLAY INVISIBLE (1200 1775);
FORCEPROP 0 LAST ROOM IO_SLOT
J 0
(1200 1775);
DISPLAY 1.021277 (1200 1775);
PAINT ORANGE (1200 1775);
DISPLAY INVISIBLE (1200 1775);
FORCEPROP 2 LAST CDS_LOCATION R9T3
J 0
(1195 1675);
DISPLAY 0.617021 (1195 1675);
PAINT AQUA (1195 1675);
DISPLAY INVISIBLE (1195 1675);
FORCEPROP 2 LAST CDS_LIB mstr_discrete
J 0
(1150 1550);
PAINT ORANGE (1150 1550);
DISPLAY INVISIBLE (1150 1550);
FORCEPROP 0 LAST CDS_SEC 1
J 0
(1200 1725);
PAINT MONO (1200 1725);
DISPLAY INVISIBLE (1200 1725);
FORCEADD OFFPAGE..2
(1775 1750);
FORCEPROP 2 LAST $XR0 199 
J 0
(1964 1750);
DISPLAY 0.638298 (1964 1750);
PAINT MONO (1964 1750);
FORCEPROP 2 LAST PATH I65
J 0
(1975 1800);
DISPLAY 1.021277 (1975 1800);
PAINT ORANGE (1975 1800);
DISPLAY INVISIBLE (1975 1800);
FORCEPROP 2 LAST CDS_LIB mstr_standard
J 0
(1775 1750);
PAINT ORANGE (1775 1750);
DISPLAY INVISIBLE (1775 1750);
FORCEPROP 1 LAST OFFPAGE TRUE
J 0
(2100 1625);
DISPLAY 0.872340 (2100 1625);
PAINT GREEN (2100 1625);
DISPLAY INVISIBLE (2100 1625);
FORCEPROP 1 LAST COMMENT_BODY TRUE
J 0
(1730 1655);
DISPLAY 0.872340 (1730 1655);
PAINT GREEN (1730 1655);
DISPLAY INVISIBLE (1730 1655);
FORCEADD OFFPAGE..2
(2325 825);
FORCEPROP 2 LAST $XR2 198 
J 0
(2754 825);
DISPLAY 0.638298 (2754 825);
PAINT MONO (2754 825);
FORCEPROP 2 LAST $XR1 191 
J 0
(2634 825);
DISPLAY 0.638298 (2634 825);
PAINT MONO (2634 825);
FORCEPROP 2 LAST $XR0 161 
J 0
(2514 825);
DISPLAY 0.638298 (2514 825);
PAINT MONO (2514 825);
FORCEPROP 2 LAST PATH I66
J 0
(2775 875);
DISPLAY 1.021277 (2775 875);
PAINT ORANGE (2775 875);
DISPLAY INVISIBLE (2775 875);
FORCEPROP 2 LAST CDS_LIB mstr_standard
J 0
(2325 825);
PAINT ORANGE (2325 825);
DISPLAY INVISIBLE (2325 825);
FORCEPROP 1 LAST OFFPAGE TRUE
J 0
(2650 700);
DISPLAY 0.872340 (2650 700);
PAINT GREEN (2650 700);
DISPLAY INVISIBLE (2650 700);
FORCEPROP 1 LAST COMMENT_BODY TRUE
J 0
(2280 730);
DISPLAY 0.872340 (2280 730);
PAINT GREEN (2280 730);
DISPLAY INVISIBLE (2280 730);
FORCEADD GND..1
(900 2400);
FORCEPROP 3 LASTPIN (900 2450) SIG_NAME GND\g
J 0
(910 2460);
DISPLAY 0.659574 (910 2460);
PAINT MONO (910 2460);
DISPLAY INVISIBLE (910 2460);
FORCEPROP 2 LAST CDS_LIB mstr_symbols
J 0
(900 2400);
PAINT MONO (900 2400);
DISPLAY INVISIBLE (900 2400);
FORCEPROP 1 LAST SIZE 1B
J 0
(975 2350);
DISPLAY 0.872340 (975 2350);
PAINT GREEN (975 2350);
DISPLAY INVISIBLE (975 2350);
FORCEPROP 1 LAST VOLTAGE 0
J 0
(900 2400);
PAINT SKYBLUE (900 2400);
DISPLAY INVISIBLE (900 2400);
FORCEPROP 2 LAST BOM_COST NT_BASE_VRD
J 0
(600 2475);
DISPLAY 0.617021 (600 2475);
PAINT ORANGE (600 2475);
DISPLAY INVISIBLE (600 2475);
FORCEPROP 2 LAST ROOM P2V5_LAN_AUX_VR
J 0
(600 2475);
DISPLAY 0.617021 (600 2475);
PAINT ORANGE (600 2475);
DISPLAY INVISIBLE (600 2475);
FORCEPROP 1 LAST PATH I67
J 0
(975 2400);
DISPLAY 0.872340 (975 2400);
PAINT AQUA (975 2400);
DISPLAY INVISIBLE (975 2400);
FORCEPROP 1 LAST BODY_TYPE PLUMBING
J 0
(855 2357);
DISPLAY 0.340426 (855 2357);
PAINT GREEN (855 2357);
DISPLAY INVISIBLE (855 2357);
FORCEPROP 1 LAST HDL_POWER GND
J 0
(900 2550);
DISPLAY 0.872340 (900 2550);
PAINT GREEN (900 2550);
DISPLAY INVISIBLE (900 2550);
FORCEADD RES..2
R 2
(1050 1900);
FORCEPROP 1 LAST LOCATION R9T6
J 2
(1005 2025);
DISPLAY 0.617021 (1005 2025);
PAINT AQUA (1005 2025);
FORCEPROP 1 LAST PACK_TYPE 0402
J 2
(885 1825);
DISPLAY 0.617021 (885 1825);
PAINT SKYBLUE (885 1825);
FORCEPROP 1 LASTPIN (1050 2000) $PN 1
J 2
(1045 1962);
DISPLAY 0.617021 (1045 1962);
PAINT ORANGE (1045 1962);
FORCEPROP 1 LAST TOLERANCE 1%
J 2
(1005 1925);
DISPLAY 0.617021 (1005 1925);
PAINT SKYBLUE (1005 1925);
FORCEPROP 1 LAST WATTAGE 1/16W
J 2
(1010 1875);
DISPLAY 0.617021 (1010 1875);
PAINT SKYBLUE (1010 1875);
FORCEPROP 1 LAST MATERIAL CHIP
J 2
(1010 1825);
DISPLAY 0.617021 (1010 1825);
PAINT SKYBLUE (1010 1825);
FORCEPROP 1 LASTPIN (1050 1800) $PN 2
J 2
(1045 1810);
DISPLAY 0.617021 (1045 1810);
PAINT ORANGE (1045 1810);
FORCEPROP 1 LAST PART_NUMBER G21796-107
J 2
(1010 1775);
DISPLAY 0.617021 (1010 1775);
PAINT BLUE (1010 1775);
FORCEPROP 1 LAST VALUE 15.0K
J 2
(1005 1975);
DISPLAY 0.617021 (1005 1975);
PAINT SKYBLUE (1005 1975);
FORCEPROP 1 LAST PATH I68
J 2
(1000 2075);
DISPLAY 0.978723 (1000 2075);
PAINT WHITE (1000 2075);
DISPLAY INVISIBLE (1000 2075);
FORCEPROP 0 LAST CDS_SEC 1
J 0
(1025 2075);
PAINT MONO (1025 2075);
DISPLAY INVISIBLE (1025 2075);
FORCEPROP 2 LAST CDS_LIB mstr_discrete
J 2
(1050 1900);
PAINT ORANGE (1050 1900);
DISPLAY INVISIBLE (1050 1900);
FORCEPROP 2 LAST CDS_LOCATION R9T6
J 2
(1005 2025);
DISPLAY 0.617021 (1005 2025);
PAINT AQUA (1005 2025);
DISPLAY INVISIBLE (1005 2025);
FORCEPROP 0 LAST ROOM IO_SLOT
J 2
(1000 2125);
DISPLAY 1.021277 (1000 2125);
PAINT ORANGE (1000 2125);
DISPLAY INVISIBLE (1000 2125);
FORCEPROP 2 LAST SEC_TYPE 0402
J 2
(1000 2125);
DISPLAY 1.021277 (1000 2125);
PAINT ORANGE (1000 2125);
DISPLAY INVISIBLE (1000 2125);
FORCEPROP 0 LAST BOM_COST IO_SLOT
J 2
(1000 2225);
DISPLAY 1.021277 (1000 2225);
PAINT ORANGE (1000 2225);
DISPLAY INVISIBLE (1000 2225);
FORCEPROP 2 LAST SEC 1
J 2
(1000 2125);
DISPLAY 0.680851 (1000 2125);
PAINT MONO (1000 2125);
DISPLAY INVISIBLE (1000 2125);
FORCEADD P12V_PSU..1
(1050 2100);
FORCEPROP 3 LASTPIN (1050 2050) SIG_NAME P12V_PSU\g
J 0
(1060 2060);
DISPLAY 0.659574 (1060 2060);
PAINT MONO (1060 2060);
DISPLAY INVISIBLE (1060 2060);
FORCEPROP 1 LAST PATH I69
J 0
(1100 2125);
DISPLAY 0.872340 (1100 2125);
PAINT AQUA (1100 2125);
DISPLAY INVISIBLE (1100 2125);
FORCEPROP 1 LAST VOLTAGE 12.0
J 0
(1005 2057);
DISPLAY 0.340426 (1005 2057);
PAINT SKYBLUE (1005 2057);
DISPLAY INVISIBLE (1005 2057);
FORCEPROP 2 LAST ROOM P2V5_LAN_AUX_VR
J 0
(1050 2200);
DISPLAY 0.617021 (1050 2200);
PAINT ORANGE (1050 2200);
DISPLAY INVISIBLE (1050 2200);
FORCEPROP 2 LAST BOM_COST NT_BASE_VRD
J 0
(1050 2200);
DISPLAY 0.617021 (1050 2200);
PAINT ORANGE (1050 2200);
DISPLAY INVISIBLE (1050 2200);
FORCEPROP 2 LAST CDS_LIB mstr_symbols
J 0
(1050 2100);
PAINT ORANGE (1050 2100);
DISPLAY INVISIBLE (1050 2100);
FORCEPROP 1 LAST BODY_TYPE PLUMBING
J 0
(1005 2057);
DISPLAY 0.340426 (1005 2057);
PAINT GREEN (1005 2057);
DISPLAY INVISIBLE (1005 2057);
FORCEPROP 1 LAST HDL_POWER P12V_PSU
J 1
(1050 2150);
DISPLAY 0.872340 (1050 2150);
PAINT GREEN (1050 2150);
DISPLAY INVISIBLE (1050 2150);
FORCEADD OFFPAGE..1
(-2875 2275);
FORCEPROP 2 LAST $XR0 182 
J 0
(-3127 2275);
DISPLAY 0.638298 (-3127 2275);
PAINT MONO (-3127 2275);
FORCEPROP 2 LAST PATH I7
J 0
(-3125 2325);
DISPLAY 1.021277 (-3125 2325);
PAINT ORANGE (-3125 2325);
DISPLAY INVISIBLE (-3125 2325);
FORCEPROP 2 LAST CDS_LIB mstr_standard
J 0
(-2875 2275);
PAINT ORANGE (-2875 2275);
DISPLAY INVISIBLE (-2875 2275);
FORCEPROP 1 LAST OFFPAGE TRUE
J 0
(-2550 2150);
DISPLAY 0.872340 (-2550 2150);
PAINT GREEN (-2550 2150);
DISPLAY INVISIBLE (-2550 2150);
FORCEPROP 1 LAST COMMENT_BODY TRUE
J 0
(-2750 2175);
DISPLAY 0.872340 (-2750 2175);
PAINT GREEN (-2750 2175);
DISPLAY INVISIBLE (-2750 2175);
FORCEADD CAP..2
(1775 2550);
FORCEPROP 1 LAST MATERIAL X7R
J 0
(2000 2525);
DISPLAY 0.617021 (2000 2525);
PAINT SKYBLUE (2000 2525);
FORCEPROP 1 LAST TOLERANCE 10%
J 2
(2200 2525);
DISPLAY 0.617021 (2200 2525);
PAINT SKYBLUE (2200 2525);
FORCEPROP 1 LAST LOCATION C1F14
J 1
(1775 2625);
DISPLAY 0.617021 (1775 2625);
PAINT AQUA (1775 2625);
FORCEPROP 1 LAST PACK_TYPE 0402
J 1
(2300 2525);
DISPLAY 0.617021 (2300 2525);
PAINT SKYBLUE (2300 2525);
FORCEPROP 1 LASTPIN (1875 2550) $PN 2
J 0
(1860 2565);
DISPLAY 0.617021 (1860 2565);
PAINT ORANGE (1860 2565);
FORCEPROP 1 LASTPIN (1675 2550) $PN 1
J 0
(1665 2565);
DISPLAY 0.617021 (1665 2565);
PAINT ORANGE (1665 2565);
FORCEPROP 1 LAST VOLTAGE 16V
J 0
(1875 2525);
DISPLAY 0.617021 (1875 2525);
PAINT SKYBLUE (1875 2525);
FORCEPROP 1 LAST PART_NUMBER A36096-155
J 1
(2000 2625);
DISPLAY 0.617021 (2000 2625);
PAINT BLUE (2000 2625);
FORCEPROP 1 LAST VALUE 0.22UF
J 2
(1725 2500);
DISPLAY 0.617021 (1725 2500);
PAINT SKYBLUE (1725 2500);
FORCEPROP 1 LAST PATH I70
J 0
(1775 2750);
DISPLAY 0.978723 (1775 2750);
PAINT WHITE (1775 2750);
DISPLAY INVISIBLE (1775 2750);
FORCEPROP 0 LAST CDS_SEC 1
J 0
(2000 2675);
PAINT MONO (2000 2675);
DISPLAY INVISIBLE (2000 2675);
FORCEPROP 2 LAST CDS_LIB mstr_discrete
J 0
(1775 2550);
PAINT ORANGE (1775 2550);
DISPLAY INVISIBLE (1775 2550);
FORCEPROP 2 LAST CDS_LOCATION C1F14
J 1
(1775 2625);
DISPLAY 0.617021 (1775 2625);
PAINT AQUA (1775 2625);
DISPLAY INVISIBLE (1775 2625);
FORCEPROP 0 LAST BOM_COST IO_SLOT
J 0
(1775 2700);
DISPLAY 1.021277 (1775 2700);
PAINT ORANGE (1775 2700);
DISPLAY INVISIBLE (1775 2700);
FORCEPROP 0 LAST ROOM IO_SLOT
J 0
(1775 2750);
DISPLAY 1.021277 (1775 2750);
PAINT ORANGE (1775 2750);
DISPLAY INVISIBLE (1775 2750);
FORCEPROP 2 LAST SEC_TYPE 0402
J 0
(1775 2800);
DISPLAY 1.021277 (1775 2800);
PAINT ORANGE (1775 2800);
DISPLAY INVISIBLE (1775 2800);
FORCEPROP 2 LAST SEC 1
J 0
(1775 2800);
DISPLAY 0.680851 (1775 2800);
PAINT MONO (1775 2800);
DISPLAY INVISIBLE (1775 2800);
FORCEADD CAP..2
(1775 2700);
FORCEPROP 1 LAST PACK_TYPE 0402
J 1
(2300 2675);
DISPLAY 0.617021 (2300 2675);
PAINT SKYBLUE (2300 2675);
FORCEPROP 1 LAST VOLTAGE 16V
J 0
(1875 2675);
DISPLAY 0.617021 (1875 2675);
PAINT SKYBLUE (1875 2675);
FORCEPROP 1 LAST PART_NUMBER A36096-155
J 1
(2000 2775);
DISPLAY 0.617021 (2000 2775);
PAINT BLUE (2000 2775);
FORCEPROP 1 LAST LOCATION C1F17
J 1
(1775 2750);
DISPLAY 0.617021 (1775 2750);
PAINT AQUA (1775 2750);
FORCEPROP 1 LASTPIN (1875 2700) $PN 2
J 0
(1860 2715);
DISPLAY 0.617021 (1860 2715);
PAINT ORANGE (1860 2715);
FORCEPROP 1 LASTPIN (1675 2700) $PN 1
J 0
(1665 2715);
DISPLAY 0.617021 (1665 2715);
PAINT ORANGE (1665 2715);
FORCEPROP 1 LAST MATERIAL X7R
J 0
(2000 2675);
DISPLAY 0.617021 (2000 2675);
PAINT SKYBLUE (2000 2675);
FORCEPROP 1 LAST TOLERANCE 10%
J 2
(2200 2675);
DISPLAY 0.617021 (2200 2675);
PAINT SKYBLUE (2200 2675);
FORCEPROP 1 LAST VALUE 0.22UF
J 2
(1725 2650);
DISPLAY 0.617021 (1725 2650);
PAINT SKYBLUE (1725 2650);
FORCEPROP 1 LAST PATH I71
J 0
(1775 2900);
DISPLAY 0.978723 (1775 2900);
PAINT WHITE (1775 2900);
DISPLAY INVISIBLE (1775 2900);
FORCEPROP 0 LAST CDS_SEC 1
J 0
(2000 2825);
PAINT MONO (2000 2825);
DISPLAY INVISIBLE (2000 2825);
FORCEPROP 2 LAST CDS_LIB mstr_discrete
J 0
(1775 2700);
PAINT ORANGE (1775 2700);
DISPLAY INVISIBLE (1775 2700);
FORCEPROP 2 LAST CDS_LOCATION C1F17
J 1
(1775 2775);
DISPLAY 0.617021 (1775 2775);
PAINT AQUA (1775 2775);
DISPLAY INVISIBLE (1775 2775);
FORCEPROP 0 LAST ROOM IO_SLOT
J 0
(1775 2900);
DISPLAY 1.021277 (1775 2900);
PAINT ORANGE (1775 2900);
DISPLAY INVISIBLE (1775 2900);
FORCEPROP 2 LAST SEC 1
J 0
(1775 2950);
DISPLAY 0.680851 (1775 2950);
PAINT MONO (1775 2950);
DISPLAY INVISIBLE (1775 2950);
FORCEPROP 2 LAST SEC_TYPE 0402
J 0
(1775 2950);
DISPLAY 1.021277 (1775 2950);
PAINT ORANGE (1775 2950);
DISPLAY INVISIBLE (1775 2950);
FORCEPROP 0 LAST BOM_COST IO_SLOT
J 0
(1775 2850);
DISPLAY 1.021277 (1775 2850);
PAINT ORANGE (1775 2850);
DISPLAY INVISIBLE (1775 2850);
FORCEADD CAP..2
(1775 2850);
FORCEPROP 1 LAST PACK_TYPE 0402
J 1
(2300 2825);
DISPLAY 0.617021 (2300 2825);
PAINT SKYBLUE (2300 2825);
FORCEPROP 1 LASTPIN (1875 2850) $PN 2
J 0
(1860 2865);
DISPLAY 0.617021 (1860 2865);
PAINT ORANGE (1860 2865);
FORCEPROP 1 LAST TOLERANCE 10%
J 2
(2200 2825);
DISPLAY 0.617021 (2200 2825);
PAINT SKYBLUE (2200 2825);
FORCEPROP 1 LAST MATERIAL X7R
J 0
(2000 2825);
DISPLAY 0.617021 (2000 2825);
PAINT SKYBLUE (2000 2825);
FORCEPROP 1 LAST VALUE 0.22UF
J 2
(1700 2800);
DISPLAY 0.617021 (1700 2800);
PAINT SKYBLUE (1700 2800);
FORCEPROP 1 LAST PART_NUMBER A36096-155
J 1
(2000 2925);
DISPLAY 0.617021 (2000 2925);
PAINT BLUE (2000 2925);
FORCEPROP 1 LASTPIN (1675 2850) $PN 1
J 0
(1665 2865);
DISPLAY 0.617021 (1665 2865);
PAINT ORANGE (1665 2865);
FORCEPROP 1 LAST LOCATION C1F18
J 1
(1775 2925);
DISPLAY 0.617021 (1775 2925);
PAINT AQUA (1775 2925);
FORCEPROP 1 LAST VOLTAGE 16V
J 0
(1875 2825);
DISPLAY 0.617021 (1875 2825);
PAINT SKYBLUE (1875 2825);
FORCEPROP 1 LAST PATH I72
J 0
(1775 3050);
DISPLAY 0.978723 (1775 3050);
PAINT WHITE (1775 3050);
DISPLAY INVISIBLE (1775 3050);
FORCEPROP 0 LAST CDS_SEC 1
J 0
(2000 2975);
PAINT MONO (2000 2975);
DISPLAY INVISIBLE (2000 2975);
FORCEPROP 0 LAST BOM_COST IO_SLOT
J 0
(1775 3000);
DISPLAY 1.021277 (1775 3000);
PAINT ORANGE (1775 3000);
DISPLAY INVISIBLE (1775 3000);
FORCEPROP 2 LAST CDS_LIB mstr_discrete
J 0
(1775 2850);
PAINT ORANGE (1775 2850);
DISPLAY INVISIBLE (1775 2850);
FORCEPROP 2 LAST CDS_LOCATION C1F18
J 1
(1775 2925);
DISPLAY 0.617021 (1775 2925);
PAINT AQUA (1775 2925);
DISPLAY INVISIBLE (1775 2925);
FORCEPROP 0 LAST ROOM IO_SLOT
J 0
(1775 3050);
DISPLAY 1.021277 (1775 3050);
PAINT ORANGE (1775 3050);
DISPLAY INVISIBLE (1775 3050);
FORCEPROP 2 LAST SEC 1
J 0
(1775 3100);
DISPLAY 0.680851 (1775 3100);
PAINT MONO (1775 3100);
DISPLAY INVISIBLE (1775 3100);
FORCEPROP 2 LAST SEC_TYPE 0402
J 0
(1775 3100);
DISPLAY 1.021277 (1775 3100);
PAINT ORANGE (1775 3100);
DISPLAY INVISIBLE (1775 3100);
FORCEADD CAP..2
(1825 3100);
FORCEPROP 1 LAST PACK_TYPE 0402
J 1
(2350 3075);
DISPLAY 0.617021 (2350 3075);
PAINT SKYBLUE (2350 3075);
FORCEPROP 1 LASTPIN (1925 3100) $PN 2
J 0
(1910 3115);
DISPLAY 0.617021 (1910 3115);
PAINT ORANGE (1910 3115);
FORCEPROP 1 LAST MATERIAL X7R
J 0
(2050 3075);
DISPLAY 0.617021 (2050 3075);
PAINT SKYBLUE (2050 3075);
FORCEPROP 1 LASTPIN (1725 3100) $PN 1
J 0
(1715 3115);
DISPLAY 0.617021 (1715 3115);
PAINT ORANGE (1715 3115);
FORCEPROP 1 LAST LOCATION C1F8
J 1
(1825 3175);
DISPLAY 0.617021 (1825 3175);
PAINT AQUA (1825 3175);
FORCEPROP 1 LAST PART_NUMBER A36096-155
J 1
(2025 3150);
DISPLAY 0.617021 (2025 3150);
PAINT BLUE (2025 3150);
FORCEPROP 1 LAST TOLERANCE 10%
J 2
(2250 3075);
DISPLAY 0.617021 (2250 3075);
PAINT SKYBLUE (2250 3075);
FORCEPROP 1 LAST VALUE 0.22UF
J 2
(1750 3050);
DISPLAY 0.617021 (1750 3050);
PAINT SKYBLUE (1750 3050);
FORCEPROP 1 LAST VOLTAGE 16V
J 0
(1925 3075);
DISPLAY 0.617021 (1925 3075);
PAINT SKYBLUE (1925 3075);
FORCEPROP 1 LAST PATH I73
J 0
(1825 3300);
DISPLAY 0.978723 (1825 3300);
PAINT WHITE (1825 3300);
DISPLAY INVISIBLE (1825 3300);
FORCEPROP 0 LAST CDS_SEC 1
J 0
(1825 3225);
PAINT MONO (1825 3225);
DISPLAY INVISIBLE (1825 3225);
FORCEPROP 2 LAST CDS_LOCATION C1F8
J 1
(1825 3175);
DISPLAY 0.617021 (1825 3175);
PAINT AQUA (1825 3175);
DISPLAY INVISIBLE (1825 3175);
FORCEPROP 0 LAST BOM_COST IO_SLOT
J 0
(1825 3250);
DISPLAY 1.021277 (1825 3250);
PAINT ORANGE (1825 3250);
DISPLAY INVISIBLE (1825 3250);
FORCEPROP 2 LAST CDS_LIB mstr_discrete
J 0
(1825 3100);
PAINT ORANGE (1825 3100);
DISPLAY INVISIBLE (1825 3100);
FORCEPROP 0 LAST ROOM IO_SLOT
J 0
(1825 3300);
DISPLAY 1.021277 (1825 3300);
PAINT ORANGE (1825 3300);
DISPLAY INVISIBLE (1825 3300);
FORCEPROP 2 LAST SEC_TYPE 0402
J 0
(1825 3350);
DISPLAY 1.021277 (1825 3350);
PAINT ORANGE (1825 3350);
DISPLAY INVISIBLE (1825 3350);
FORCEPROP 2 LAST SEC 1
J 0
(1825 3350);
DISPLAY 0.680851 (1825 3350);
PAINT MONO (1825 3350);
DISPLAY INVISIBLE (1825 3350);
FORCEADD CAP..2
(1825 3250);
FORCEPROP 1 LASTPIN (1925 3250) $PN 2
J 0
(1910 3265);
DISPLAY 0.617021 (1910 3265);
PAINT ORANGE (1910 3265);
FORCEPROP 1 LAST VOLTAGE 16V
J 0
(1925 3225);
DISPLAY 0.617021 (1925 3225);
PAINT SKYBLUE (1925 3225);
FORCEPROP 1 LAST LOCATION C1F11
J 1
(1825 3325);
DISPLAY 0.617021 (1825 3325);
PAINT AQUA (1825 3325);
FORCEPROP 1 LAST TOLERANCE 10%
J 2
(2250 3225);
DISPLAY 0.617021 (2250 3225);
PAINT SKYBLUE (2250 3225);
FORCEPROP 1 LASTPIN (1725 3250) $PN 1
J 0
(1715 3265);
DISPLAY 0.617021 (1715 3265);
PAINT ORANGE (1715 3265);
FORCEPROP 1 LAST PART_NUMBER A36096-155
J 1
(2075 3300);
DISPLAY 0.617021 (2075 3300);
PAINT BLUE (2075 3300);
FORCEPROP 1 LAST VALUE 0.22UF
J 2
(1750 3200);
DISPLAY 0.617021 (1750 3200);
PAINT SKYBLUE (1750 3200);
FORCEPROP 1 LAST MATERIAL X7R
J 0
(2050 3225);
DISPLAY 0.617021 (2050 3225);
PAINT SKYBLUE (2050 3225);
FORCEPROP 1 LAST PACK_TYPE 0402
J 1
(2350 3225);
DISPLAY 0.617021 (2350 3225);
PAINT SKYBLUE (2350 3225);
FORCEPROP 1 LAST PATH I74
J 0
(1825 3450);
DISPLAY 0.978723 (1825 3450);
PAINT WHITE (1825 3450);
DISPLAY INVISIBLE (1825 3450);
FORCEPROP 0 LAST CDS_SEC 1
J 0
(1825 3375);
PAINT MONO (1825 3375);
DISPLAY INVISIBLE (1825 3375);
FORCEPROP 2 LAST CDS_LIB mstr_discrete
J 0
(1825 3250);
PAINT ORANGE (1825 3250);
DISPLAY INVISIBLE (1825 3250);
FORCEPROP 2 LAST CDS_LOCATION C1F11
J 1
(1825 3325);
DISPLAY 0.617021 (1825 3325);
PAINT AQUA (1825 3325);
DISPLAY INVISIBLE (1825 3325);
FORCEPROP 2 LAST SEC 1
J 0
(1825 3500);
DISPLAY 0.680851 (1825 3500);
PAINT MONO (1825 3500);
DISPLAY INVISIBLE (1825 3500);
FORCEPROP 0 LAST BOM_COST IO_SLOT
J 0
(1825 3400);
DISPLAY 1.021277 (1825 3400);
PAINT ORANGE (1825 3400);
DISPLAY INVISIBLE (1825 3400);
FORCEPROP 2 LAST SEC_TYPE 0402
J 0
(1825 3500);
DISPLAY 1.021277 (1825 3500);
PAINT ORANGE (1825 3500);
DISPLAY INVISIBLE (1825 3500);
FORCEPROP 0 LAST ROOM IO_SLOT
J 0
(1825 3450);
DISPLAY 1.021277 (1825 3450);
PAINT ORANGE (1825 3450);
DISPLAY INVISIBLE (1825 3450);
FORCEADD CAP..2
(1825 3400);
FORCEPROP 1 LAST TOLERANCE 10%
J 2
(2250 3375);
DISPLAY 0.617021 (2250 3375);
PAINT SKYBLUE (2250 3375);
FORCEPROP 1 LAST PACK_TYPE 0402
J 1
(2350 3375);
DISPLAY 0.617021 (2350 3375);
PAINT SKYBLUE (2350 3375);
FORCEPROP 1 LASTPIN (1725 3400) $PN 1
J 0
(1715 3415);
DISPLAY 0.617021 (1715 3415);
PAINT ORANGE (1715 3415);
FORCEPROP 1 LAST VALUE 0.22UF
J 2
(1750 3350);
DISPLAY 0.617021 (1750 3350);
PAINT SKYBLUE (1750 3350);
FORCEPROP 1 LAST LOCATION C1F12
J 1
(1825 3475);
DISPLAY 0.617021 (1825 3475);
PAINT AQUA (1825 3475);
FORCEPROP 1 LAST MATERIAL X7R
J 0
(2050 3375);
DISPLAY 0.617021 (2050 3375);
PAINT SKYBLUE (2050 3375);
FORCEPROP 1 LAST VOLTAGE 16V
J 0
(1925 3375);
DISPLAY 0.617021 (1925 3375);
PAINT SKYBLUE (1925 3375);
FORCEPROP 1 LASTPIN (1925 3400) $PN 2
J 0
(1910 3415);
DISPLAY 0.617021 (1910 3415);
PAINT ORANGE (1910 3415);
FORCEPROP 1 LAST PART_NUMBER A36096-155
J 1
(2025 3475);
DISPLAY 0.617021 (2025 3475);
PAINT BLUE (2025 3475);
FORCEPROP 1 LAST PATH I75
J 0
(1825 3600);
DISPLAY 0.978723 (1825 3600);
PAINT WHITE (1825 3600);
DISPLAY INVISIBLE (1825 3600);
FORCEPROP 0 LAST CDS_SEC 1
J 0
(2025 3525);
PAINT MONO (2025 3525);
DISPLAY INVISIBLE (2025 3525);
FORCEPROP 0 LAST ROOM IO_SLOT
J 0
(1825 3600);
DISPLAY 1.021277 (1825 3600);
PAINT ORANGE (1825 3600);
DISPLAY INVISIBLE (1825 3600);
FORCEPROP 2 LAST SEC_TYPE 0402
J 0
(1825 3650);
DISPLAY 1.021277 (1825 3650);
PAINT ORANGE (1825 3650);
DISPLAY INVISIBLE (1825 3650);
FORCEPROP 2 LAST SEC 1
J 0
(1825 3650);
DISPLAY 0.680851 (1825 3650);
PAINT MONO (1825 3650);
DISPLAY INVISIBLE (1825 3650);
FORCEPROP 0 LAST BOM_COST IO_SLOT
J 0
(1825 3550);
DISPLAY 1.021277 (1825 3550);
PAINT ORANGE (1825 3550);
DISPLAY INVISIBLE (1825 3550);
FORCEPROP 2 LAST CDS_LIB mstr_discrete
J 0
(1825 3400);
PAINT ORANGE (1825 3400);
DISPLAY INVISIBLE (1825 3400);
FORCEPROP 2 LAST CDS_LOCATION C1F12
J 1
(1825 3475);
DISPLAY 0.617021 (1825 3475);
PAINT AQUA (1825 3475);
DISPLAY INVISIBLE (1825 3475);
FORCEADD CAP..2
(1825 3600);
FORCEPROP 1 LAST VOLTAGE 16V
J 0
(1925 3575);
DISPLAY 0.617021 (1925 3575);
PAINT SKYBLUE (1925 3575);
FORCEPROP 1 LAST MATERIAL X7R
J 0
(2050 3575);
DISPLAY 0.617021 (2050 3575);
PAINT SKYBLUE (2050 3575);
FORCEPROP 1 LAST TOLERANCE 10%
J 2
(2250 3575);
DISPLAY 0.617021 (2250 3575);
PAINT SKYBLUE (2250 3575);
FORCEPROP 1 LAST LOCATION C1F3
J 1
(1825 3675);
DISPLAY 0.617021 (1825 3675);
PAINT AQUA (1825 3675);
FORCEPROP 1 LASTPIN (1925 3600) $PN 2
J 0
(1910 3615);
DISPLAY 0.617021 (1910 3615);
PAINT ORANGE (1910 3615);
FORCEPROP 1 LASTPIN (1725 3600) $PN 1
J 0
(1715 3615);
DISPLAY 0.617021 (1715 3615);
PAINT ORANGE (1715 3615);
FORCEPROP 1 LAST PART_NUMBER A36096-155
J 1
(1975 3650);
DISPLAY 0.617021 (1975 3650);
PAINT BLUE (1975 3650);
FORCEPROP 1 LAST VALUE 0.22UF
J 2
(1750 3550);
DISPLAY 0.617021 (1750 3550);
PAINT SKYBLUE (1750 3550);
FORCEPROP 1 LAST PACK_TYPE 0402
J 1
(2350 3575);
DISPLAY 0.617021 (2350 3575);
PAINT SKYBLUE (2350 3575);
FORCEPROP 1 LAST PATH I76
J 0
(1825 3800);
DISPLAY 0.978723 (1825 3800);
PAINT WHITE (1825 3800);
DISPLAY INVISIBLE (1825 3800);
FORCEPROP 0 LAST CDS_SEC 1
J 0
(1825 3725);
PAINT MONO (1825 3725);
DISPLAY INVISIBLE (1825 3725);
FORCEPROP 2 LAST CDS_LOCATION C1F3
J 1
(1825 3675);
DISPLAY 0.617021 (1825 3675);
PAINT AQUA (1825 3675);
DISPLAY INVISIBLE (1825 3675);
FORCEPROP 0 LAST BOM_COST IO_SLOT
J 0
(1825 3750);
DISPLAY 1.021277 (1825 3750);
PAINT ORANGE (1825 3750);
DISPLAY INVISIBLE (1825 3750);
FORCEPROP 2 LAST CDS_LIB mstr_discrete
J 0
(1825 3600);
PAINT ORANGE (1825 3600);
DISPLAY INVISIBLE (1825 3600);
FORCEPROP 0 LAST ROOM IO_SLOT
J 0
(1825 3800);
DISPLAY 1.021277 (1825 3800);
PAINT ORANGE (1825 3800);
DISPLAY INVISIBLE (1825 3800);
FORCEPROP 2 LAST SEC_TYPE 0402
J 0
(1825 3850);
DISPLAY 1.021277 (1825 3850);
PAINT ORANGE (1825 3850);
DISPLAY INVISIBLE (1825 3850);
FORCEPROP 2 LAST SEC 1
J 0
(1825 3850);
DISPLAY 0.680851 (1825 3850);
PAINT MONO (1825 3850);
DISPLAY INVISIBLE (1825 3850);
FORCEADD CAP..2
(1825 3750);
FORCEPROP 1 LASTPIN (1925 3750) $PN 2
J 0
(1910 3765);
DISPLAY 0.617021 (1910 3765);
PAINT ORANGE (1910 3765);
FORCEPROP 1 LASTPIN (1725 3750) $PN 1
J 0
(1715 3765);
DISPLAY 0.617021 (1715 3765);
PAINT ORANGE (1715 3765);
FORCEPROP 1 LAST VOLTAGE 16V
J 0
(1925 3725);
DISPLAY 0.617021 (1925 3725);
PAINT SKYBLUE (1925 3725);
FORCEPROP 1 LAST PACK_TYPE 0402
J 1
(2350 3725);
DISPLAY 0.617021 (2350 3725);
PAINT SKYBLUE (2350 3725);
FORCEPROP 1 LAST MATERIAL X7R
J 0
(2050 3725);
DISPLAY 0.617021 (2050 3725);
PAINT SKYBLUE (2050 3725);
FORCEPROP 1 LAST PART_NUMBER A36096-155
J 1
(1825 3800);
DISPLAY 0.617021 (1825 3800);
PAINT BLUE (1825 3800);
FORCEPROP 1 LAST LOCATION C1F5
J 1
(1825 3850);
DISPLAY 0.617021 (1825 3850);
PAINT AQUA (1825 3850);
FORCEPROP 1 LAST TOLERANCE 10%
J 2
(2250 3725);
DISPLAY 0.617021 (2250 3725);
PAINT SKYBLUE (2250 3725);
FORCEPROP 1 LAST VALUE 0.22UF
J 2
(1750 3700);
DISPLAY 0.617021 (1750 3700);
PAINT SKYBLUE (1750 3700);
FORCEPROP 1 LAST PATH I77
J 0
(1825 3950);
DISPLAY 0.978723 (1825 3950);
PAINT WHITE (1825 3950);
DISPLAY INVISIBLE (1825 3950);
FORCEPROP 0 LAST CDS_SEC 1
J 0
(1825 3900);
PAINT MONO (1825 3900);
DISPLAY INVISIBLE (1825 3900);
FORCEPROP 2 LAST CDS_LIB mstr_discrete
J 0
(1825 3750);
PAINT ORANGE (1825 3750);
DISPLAY INVISIBLE (1825 3750);
FORCEPROP 0 LAST ROOM IO_SLOT
J 0
(1825 3950);
DISPLAY 1.021277 (1825 3950);
PAINT ORANGE (1825 3950);
DISPLAY INVISIBLE (1825 3950);
FORCEPROP 0 LAST BOM_COST IO_SLOT
J 0
(1825 3900);
DISPLAY 1.021277 (1825 3900);
PAINT ORANGE (1825 3900);
DISPLAY INVISIBLE (1825 3900);
FORCEPROP 2 LAST SEC_TYPE 0402
J 0
(1825 4000);
DISPLAY 1.021277 (1825 4000);
PAINT ORANGE (1825 4000);
DISPLAY INVISIBLE (1825 4000);
FORCEPROP 2 LAST SEC 1
J 0
(1825 4000);
DISPLAY 0.680851 (1825 4000);
PAINT MONO (1825 4000);
DISPLAY INVISIBLE (1825 4000);
FORCEPROP 2 LAST CDS_LOCATION C1F5
J 1
(1825 3850);
DISPLAY 0.617021 (1825 3850);
PAINT AQUA (1825 3850);
DISPLAY INVISIBLE (1825 3850);
FORCEADD CAP..2
(2275 2600);
FORCEPROP 1 LAST VALUE 0.22UF
J 2
(2225 2575);
DISPLAY 0.617021 (2225 2575);
PAINT SKYBLUE (2225 2575);
FORCEPROP 1 LAST LOCATION C1F15
J 1
(2300 2625);
DISPLAY 0.617021 (2300 2625);
PAINT AQUA (2300 2625);
FORCEPROP 1 LAST VOLTAGE 16V
J 0
(2375 2575);
DISPLAY 0.617021 (2375 2575);
PAINT SKYBLUE (2375 2575);
FORCEPROP 1 LASTPIN (2175 2600) $PN 1
J 0
(2165 2615);
DISPLAY 0.617021 (2165 2615);
PAINT ORANGE (2165 2615);
FORCEPROP 1 LASTPIN (2375 2600) $PN 2
J 0
(2360 2615);
DISPLAY 0.617021 (2360 2615);
PAINT ORANGE (2360 2615);
FORCEPROP 1 LAST MATERIAL X7R
J 0
(2500 2575);
DISPLAY 0.617021 (2500 2575);
PAINT SKYBLUE (2500 2575);
FORCEPROP 1 LAST TOLERANCE 10%
J 2
(2700 2575);
DISPLAY 0.617021 (2700 2575);
PAINT SKYBLUE (2700 2575);
FORCEPROP 1 LAST PACK_TYPE 0402
J 1
(2800 2575);
DISPLAY 0.617021 (2800 2575);
PAINT SKYBLUE (2800 2575);
FORCEPROP 1 LAST PART_NUMBER A36096-155
J 1
(2575 2625);
DISPLAY 0.617021 (2575 2625);
PAINT BLUE (2575 2625);
FORCEPROP 1 LAST PATH I78
J 0
(2275 2800);
DISPLAY 0.978723 (2275 2800);
PAINT WHITE (2275 2800);
DISPLAY INVISIBLE (2275 2800);
FORCEPROP 0 LAST CDS_SEC 1
J 0
(2575 2675);
PAINT MONO (2575 2675);
DISPLAY INVISIBLE (2575 2675);
FORCEPROP 2 LAST CDS_LOCATION C1F15
J 1
(2300 2650);
DISPLAY 0.617021 (2300 2650);
PAINT AQUA (2300 2650);
DISPLAY INVISIBLE (2300 2650);
FORCEPROP 0 LAST BOM_COST IO_SLOT
J 0
(2275 2750);
DISPLAY 1.021277 (2275 2750);
PAINT ORANGE (2275 2750);
DISPLAY INVISIBLE (2275 2750);
FORCEPROP 2 LAST CDS_LIB mstr_discrete
J 0
(2275 2600);
PAINT ORANGE (2275 2600);
DISPLAY INVISIBLE (2275 2600);
FORCEPROP 0 LAST ROOM IO_SLOT
J 0
(2275 2800);
DISPLAY 1.021277 (2275 2800);
PAINT ORANGE (2275 2800);
DISPLAY INVISIBLE (2275 2800);
FORCEPROP 2 LAST SEC 1
J 0
(2275 2850);
DISPLAY 0.680851 (2275 2850);
PAINT MONO (2275 2850);
DISPLAY INVISIBLE (2275 2850);
FORCEPROP 2 LAST SEC_TYPE 0402
J 0
(2275 2850);
DISPLAY 1.021277 (2275 2850);
PAINT ORANGE (2275 2850);
DISPLAY INVISIBLE (2275 2850);
FORCEADD CAP..2
(2275 2750);
FORCEPROP 1 LASTPIN (2375 2750) $PN 2
J 0
(2360 2765);
DISPLAY 0.617021 (2360 2765);
PAINT ORANGE (2360 2765);
FORCEPROP 1 LAST PART_NUMBER A36096-155
J 1
(2575 2775);
DISPLAY 0.617021 (2575 2775);
PAINT BLUE (2575 2775);
FORCEPROP 1 LAST VALUE 0.22UF
J 2
(2225 2725);
DISPLAY 0.617021 (2225 2725);
PAINT SKYBLUE (2225 2725);
FORCEPROP 1 LASTPIN (2175 2750) $PN 1
J 0
(2165 2765);
DISPLAY 0.617021 (2165 2765);
PAINT ORANGE (2165 2765);
FORCEPROP 1 LAST LOCATION C1F16
J 1
(2300 2800);
DISPLAY 0.617021 (2300 2800);
PAINT AQUA (2300 2800);
FORCEPROP 1 LAST TOLERANCE 10%
J 2
(2700 2725);
DISPLAY 0.617021 (2700 2725);
PAINT SKYBLUE (2700 2725);
FORCEPROP 1 LAST PACK_TYPE 0402
J 1
(2800 2725);
DISPLAY 0.617021 (2800 2725);
PAINT SKYBLUE (2800 2725);
FORCEPROP 1 LAST MATERIAL X7R
J 0
(2500 2725);
DISPLAY 0.617021 (2500 2725);
PAINT SKYBLUE (2500 2725);
FORCEPROP 1 LAST VOLTAGE 16V
J 0
(2375 2725);
DISPLAY 0.617021 (2375 2725);
PAINT SKYBLUE (2375 2725);
FORCEPROP 1 LAST PATH I79
J 0
(2275 2950);
DISPLAY 0.978723 (2275 2950);
PAINT WHITE (2275 2950);
DISPLAY INVISIBLE (2275 2950);
FORCEPROP 0 LAST CDS_SEC 1
J 0
(2300 2850);
PAINT MONO (2300 2850);
DISPLAY INVISIBLE (2300 2850);
FORCEPROP 2 LAST CDS_LIB mstr_discrete
J 0
(2275 2750);
PAINT ORANGE (2275 2750);
DISPLAY INVISIBLE (2275 2750);
FORCEPROP 2 LAST CDS_LOCATION C1F16
J 1
(2275 2800);
DISPLAY 0.617021 (2275 2800);
PAINT AQUA (2275 2800);
DISPLAY INVISIBLE (2275 2800);
FORCEPROP 2 LAST SEC 1
J 0
(2275 3000);
DISPLAY 0.680851 (2275 3000);
PAINT MONO (2275 3000);
DISPLAY INVISIBLE (2275 3000);
FORCEPROP 2 LAST SEC_TYPE 0402
J 0
(2275 3000);
DISPLAY 1.021277 (2275 3000);
PAINT ORANGE (2275 3000);
DISPLAY INVISIBLE (2275 3000);
FORCEPROP 0 LAST BOM_COST IO_SLOT
J 0
(2275 2900);
DISPLAY 1.021277 (2275 2900);
PAINT ORANGE (2275 2900);
DISPLAY INVISIBLE (2275 2900);
FORCEPROP 0 LAST ROOM IO_SLOT
J 0
(2275 2950);
DISPLAY 1.021277 (2275 2950);
PAINT ORANGE (2275 2950);
DISPLAY INVISIBLE (2275 2950);
FORCEADD OFFPAGE..5
(-2875 2225);
FORCEPROP 2 LAST $XR0 182 
J 0
(-3160 2225);
DISPLAY 0.638298 (-3160 2225);
PAINT MONO (-3160 2225);
FORCEPROP 2 LAST PATH I8
J 0
(-3150 2275);
DISPLAY 1.021277 (-3150 2275);
PAINT ORANGE (-3150 2275);
DISPLAY INVISIBLE (-3150 2275);
FORCEPROP 2 LAST CDS_LIB mstr_standard
J 0
(-2875 2225);
PAINT ORANGE (-2875 2225);
DISPLAY INVISIBLE (-2875 2225);
FORCEPROP 1 LAST OFFPAGE TRUE
J 0
(-2550 2100);
DISPLAY 0.872340 (-2550 2100);
PAINT GREEN (-2550 2100);
DISPLAY INVISIBLE (-2550 2100);
FORCEPROP 1 LAST COMMENT_BODY TRUE
J 0
(-2775 2150);
DISPLAY 0.872340 (-2775 2150);
PAINT GREEN (-2775 2150);
DISPLAY INVISIBLE (-2775 2150);
FORCEADD RES..1
(2650 2050);
FORCEPROP 1 LASTPIN (2550 2050) $PN 1
J 0
(2562 2062);
DISPLAY 0.617021 (2562 2062);
PAINT ORANGE (2562 2062);
FORCEPROP 1 LAST PACK_TYPE 0402
J 0
(2350 1950);
DISPLAY 0.617021 (2350 1950);
PAINT SKYBLUE (2350 1950);
FORCEPROP 1 LAST LOCATION R7D9
J 0
(2600 2100);
DISPLAY 0.617021 (2600 2100);
PAINT AQUA (2600 2100);
FORCEPROP 1 LASTPIN (2750 2050) $PN 2
J 0
(2712 2062);
DISPLAY 0.617021 (2712 2062);
PAINT ORANGE (2712 2062);
FORCEPROP 1 LAST WATTAGE 1/16W
J 2
(2550 1950);
DISPLAY 0.617021 (2550 1950);
PAINT SKYBLUE (2550 1950);
FORCEPROP 1 LAST VALUE 2.26K
J 2
(2575 2000);
DISPLAY 0.617021 (2575 2000);
PAINT SKYBLUE (2575 2000);
FORCEPROP 1 LAST TOLERANCE 1.0%
J 0
(2625 2000);
DISPLAY 0.617021 (2625 2000);
PAINT SKYBLUE (2625 2000);
FORCEPROP 1 LAST MATERIAL CHIP
J 0
(2750 2000);
DISPLAY 0.617021 (2750 2000);
PAINT SKYBLUE (2750 2000);
FORCEPROP 1 LAST PART_NUMBER G21796-311
J 0
(2850 2000);
DISPLAY 0.617021 (2850 2000);
PAINT BLUE (2850 2000);
FORCEPROP 1 LAST PATH I80
J 0
(2600 2200);
DISPLAY 0.978723 (2600 2200);
PAINT WHITE (2600 2200);
DISPLAY INVISIBLE (2600 2200);
FORCEPROP 0 LAST CDS_SEC 1
J 0
(2600 2150);
PAINT MONO (2600 2150);
DISPLAY INVISIBLE (2600 2150);
FORCEPROP 2 LAST CDS_LOCATION R7D9
J 0
(2600 2100);
DISPLAY 0.617021 (2600 2100);
PAINT AQUA (2600 2100);
DISPLAY INVISIBLE (2600 2100);
FORCEPROP 2 LAST SEC 1
J 0
(2600 2250);
DISPLAY 0.680851 (2600 2250);
PAINT MONO (2600 2250);
DISPLAY INVISIBLE (2600 2250);
FORCEPROP 2 LAST SEC_TYPE 0402
J 0
(2600 2250);
DISPLAY 1.021277 (2600 2250);
PAINT ORANGE (2600 2250);
DISPLAY INVISIBLE (2600 2250);
FORCEPROP 0 LAST ROOM IO_SLOT
J 0
(2600 2200);
DISPLAY 1.021277 (2600 2200);
PAINT ORANGE (2600 2200);
DISPLAY INVISIBLE (2600 2200);
FORCEPROP 2 LAST CDS_LIB mstr_discrete
J 0
(2650 2050);
PAINT ORANGE (2650 2050);
DISPLAY INVISIBLE (2650 2050);
FORCEADD RES..1
(2650 1875);
FORCEPROP 1 LAST VALUE 2.26K
J 2
(2575 1825);
DISPLAY 0.617021 (2575 1825);
PAINT SKYBLUE (2575 1825);
FORCEPROP 1 LAST PACK_TYPE 0402
J 0
(2350 1775);
DISPLAY 0.617021 (2350 1775);
PAINT SKYBLUE (2350 1775);
FORCEPROP 1 LAST MATERIAL CHIP
J 0
(2750 1825);
DISPLAY 0.617021 (2750 1825);
PAINT SKYBLUE (2750 1825);
FORCEPROP 1 LAST PART_NUMBER G21796-311
J 0
(2875 1825);
DISPLAY 0.617021 (2875 1825);
PAINT BLUE (2875 1825);
FORCEPROP 1 LASTPIN (2550 1875) $PN 1
J 0
(2562 1887);
DISPLAY 0.617021 (2562 1887);
PAINT ORANGE (2562 1887);
FORCEPROP 1 LAST LOCATION R3P61
J 0
(2600 1925);
DISPLAY 0.617021 (2600 1925);
PAINT AQUA (2600 1925);
FORCEPROP 1 LASTPIN (2750 1875) $PN 2
J 0
(2712 1887);
DISPLAY 0.617021 (2712 1887);
PAINT ORANGE (2712 1887);
FORCEPROP 1 LAST TOLERANCE 1.0%
J 0
(2625 1825);
DISPLAY 0.617021 (2625 1825);
PAINT SKYBLUE (2625 1825);
FORCEPROP 1 LAST WATTAGE 1/16W
J 2
(2600 1775);
DISPLAY 0.617021 (2600 1775);
PAINT SKYBLUE (2600 1775);
FORCEPROP 1 LAST PATH I81
J 0
(2600 2025);
DISPLAY 0.978723 (2600 2025);
PAINT WHITE (2600 2025);
DISPLAY INVISIBLE (2600 2025);
FORCEPROP 0 LAST CDS_SEC 1
J 0
(2600 1975);
PAINT MONO (2600 1975);
DISPLAY INVISIBLE (2600 1975);
FORCEPROP 2 LAST CDS_LOCATION R3P61
J 0
(2600 1925);
DISPLAY 0.617021 (2600 1925);
PAINT AQUA (2600 1925);
DISPLAY INVISIBLE (2600 1925);
FORCEPROP 0 LAST ROOM IO_SLOT
J 0
(2600 2025);
DISPLAY 1.021277 (2600 2025);
PAINT ORANGE (2600 2025);
DISPLAY INVISIBLE (2600 2025);
FORCEPROP 2 LAST SEC_TYPE 0402
J 0
(2600 2075);
DISPLAY 1.021277 (2600 2075);
PAINT ORANGE (2600 2075);
DISPLAY INVISIBLE (2600 2075);
FORCEPROP 2 LAST SEC 1
J 0
(2600 2075);
DISPLAY 0.680851 (2600 2075);
PAINT MONO (2600 2075);
DISPLAY INVISIBLE (2600 2075);
FORCEPROP 2 LAST CDS_LIB mstr_discrete
J 0
(2650 1875);
PAINT ORANGE (2650 1875);
DISPLAY INVISIBLE (2650 1875);
FORCEADD RES..1
(2650 2225);
FORCEPROP 1 LASTPIN (2750 2225) $PN 2
J 0
(2712 2237);
DISPLAY 0.617021 (2712 2237);
PAINT ORANGE (2712 2237);
FORCEPROP 1 LAST PACK_TYPE 0402
J 0
(2350 2125);
DISPLAY 0.617021 (2350 2125);
PAINT SKYBLUE (2350 2125);
FORCEPROP 1 LAST WATTAGE 1/16W
J 2
(2575 2125);
DISPLAY 0.617021 (2575 2125);
PAINT SKYBLUE (2575 2125);
FORCEPROP 1 LAST VALUE 2.26K
J 2
(2575 2175);
DISPLAY 0.617021 (2575 2175);
PAINT SKYBLUE (2575 2175);
FORCEPROP 1 LASTPIN (2550 2225) $PN 1
J 0
(2562 2237);
DISPLAY 0.617021 (2562 2237);
PAINT ORANGE (2562 2237);
FORCEPROP 1 LAST MATERIAL CHIP
J 0
(2750 2175);
DISPLAY 0.617021 (2750 2175);
PAINT SKYBLUE (2750 2175);
FORCEPROP 1 LAST PART_NUMBER G21796-311
J 0
(2850 2175);
DISPLAY 0.617021 (2850 2175);
PAINT BLUE (2850 2175);
FORCEPROP 1 LAST LOCATION R7D5
J 0
(2600 2275);
DISPLAY 0.617021 (2600 2275);
PAINT AQUA (2600 2275);
FORCEPROP 1 LAST TOLERANCE 1.0%
J 0
(2625 2175);
DISPLAY 0.617021 (2625 2175);
PAINT SKYBLUE (2625 2175);
FORCEPROP 1 LAST PATH I82
J 0
(2600 2375);
DISPLAY 0.978723 (2600 2375);
PAINT WHITE (2600 2375);
DISPLAY INVISIBLE (2600 2375);
FORCEPROP 0 LAST CDS_SEC 1
J 0
(2600 2325);
PAINT MONO (2600 2325);
DISPLAY INVISIBLE (2600 2325);
FORCEPROP 2 LAST CDS_LOCATION R7D5
J 0
(2600 2275);
DISPLAY 0.617021 (2600 2275);
PAINT AQUA (2600 2275);
DISPLAY INVISIBLE (2600 2275);
FORCEPROP 2 LAST SEC 1
J 0
(2600 2425);
DISPLAY 0.680851 (2600 2425);
PAINT MONO (2600 2425);
DISPLAY INVISIBLE (2600 2425);
FORCEPROP 2 LAST SEC_TYPE 0402
J 0
(2600 2425);
DISPLAY 1.021277 (2600 2425);
PAINT ORANGE (2600 2425);
DISPLAY INVISIBLE (2600 2425);
FORCEPROP 0 LAST ROOM IO_SLOT
J 0
(2600 2375);
DISPLAY 1.021277 (2600 2375);
PAINT ORANGE (2600 2375);
DISPLAY INVISIBLE (2600 2375);
FORCEPROP 2 LAST CDS_LIB mstr_discrete
J 0
(2650 2225);
PAINT ORANGE (2650 2225);
DISPLAY INVISIBLE (2650 2225);
FORCEADD P3V3_STBY..1
(2325 2375);
FORCEPROP 3 LASTPIN (2325 2325) SIG_NAME P3V3_STBY\g
J 0
(2335 2335);
DISPLAY 0.659574 (2335 2335);
PAINT MONO (2335 2335);
DISPLAY INVISIBLE (2335 2335);
FORCEPROP 1 LAST PATH I83
J 0
(2370 2377);
DISPLAY 0.340426 (2370 2377);
PAINT GREEN (2370 2377);
DISPLAY INVISIBLE (2370 2377);
FORCEPROP 2 LAST CDS_LIB mstr_symbols
J 0
(2325 2375);
PAINT ORANGE (2325 2375);
DISPLAY INVISIBLE (2325 2375);
FORCEPROP 1 LAST SIZE 1B
J 0
(2370 2397);
DISPLAY 0.340426 (2370 2397);
PAINT GREEN (2370 2397);
DISPLAY INVISIBLE (2370 2397);
FORCEPROP 1 LAST VOLTAGE 3.3V
J 0
(2280 2332);
DISPLAY 0.340426 (2280 2332);
PAINT SKYBLUE (2280 2332);
DISPLAY INVISIBLE (2280 2332);
FORCEPROP 1 LAST BODY_TYPE PLUMBING
J 0
(2280 2332);
DISPLAY 0.340426 (2280 2332);
PAINT GREEN (2280 2332);
DISPLAY INVISIBLE (2280 2332);
FORCEPROP 1 LAST HDL_POWER P3V3_STBY
J 0
(2025 2250);
DISPLAY 0.872340 (2025 2250);
PAINT ORANGE (2025 2250);
DISPLAY INVISIBLE (2025 2250);
FORCEADD TAP..6
R 2
(2925 2700);
FORCEPROP 3 LASTPIN (2875 2700) SIG_NAME P3E_CPU1_PE3_MP_TXP<1>
J 0
(2885 2710);
DISPLAY 0.659574 (2885 2710);
PAINT MONO (2885 2710);
DISPLAY INVISIBLE (2885 2710);
FORCEPROP 1 LASTPIN (2875 2700) BN 1
J 2
(2927 2708);
DISPLAY 0.617021 (2927 2708);
PAINT GREEN (2927 2708);
FORCEPROP 1 LAST PATH I84
J 2
(2927 2700);
DISPLAY 0.872340 (2927 2700);
PAINT GREEN (2927 2700);
DISPLAY INVISIBLE (2927 2700);
FORCEPROP 2 LAST CDS_LIB mstr_standard
J 0
(2925 2700);
PAINT ORANGE (2925 2700);
DISPLAY INVISIBLE (2925 2700);
FORCEPROP 1 LAST BODY_TYPE PLUMBING
J 2
(2925 2650);
DISPLAY 1.234043 (2925 2650);
PAINT GREEN (2925 2650);
DISPLAY INVISIBLE (2925 2650);
FORCEPROP 1 LAST HDL_TAP TRUE
J 2
(2600 2575);
DISPLAY 1.234043 (2600 2575);
PAINT GREEN (2600 2575);
DISPLAY INVISIBLE (2600 2575);
FORCEADD TAP..6
R 2
(2925 2550);
FORCEPROP 3 LASTPIN (2875 2550) SIG_NAME P3E_CPU1_PE3_MP_TXP<2>
J 0
(2885 2560);
DISPLAY 0.659574 (2885 2560);
PAINT MONO (2885 2560);
DISPLAY INVISIBLE (2885 2560);
FORCEPROP 1 LASTPIN (2875 2550) BN 2
J 2
(2927 2558);
DISPLAY 0.617021 (2927 2558);
PAINT GREEN (2927 2558);
FORCEPROP 1 LAST PATH I85
J 2
(2927 2550);
DISPLAY 0.872340 (2927 2550);
PAINT GREEN (2927 2550);
DISPLAY INVISIBLE (2927 2550);
FORCEPROP 2 LAST CDS_LIB mstr_standard
J 0
(2925 2550);
PAINT ORANGE (2925 2550);
DISPLAY INVISIBLE (2925 2550);
FORCEPROP 1 LAST BODY_TYPE PLUMBING
J 2
(2925 2500);
DISPLAY 1.234043 (2925 2500);
PAINT GREEN (2925 2500);
DISPLAY INVISIBLE (2925 2500);
FORCEPROP 1 LAST HDL_TAP TRUE
J 2
(2600 2425);
DISPLAY 1.234043 (2600 2425);
PAINT GREEN (2600 2425);
DISPLAY INVISIBLE (2600 2425);
FORCEADD CAP..2
(2275 2900);
FORCEPROP 1 LASTPIN (2375 2900) $PN 2
J 0
(2360 2915);
DISPLAY 0.617021 (2360 2915);
PAINT ORANGE (2360 2915);
FORCEPROP 1 LAST LOCATION C1F20
J 1
(2275 2950);
DISPLAY 0.617021 (2275 2950);
PAINT AQUA (2275 2950);
FORCEPROP 1 LASTPIN (2175 2900) $PN 1
J 0
(2165 2915);
DISPLAY 0.617021 (2165 2915);
PAINT ORANGE (2165 2915);
FORCEPROP 1 LAST MATERIAL X7R
J 0
(2500 2875);
DISPLAY 0.617021 (2500 2875);
PAINT SKYBLUE (2500 2875);
FORCEPROP 1 LAST TOLERANCE 10%
J 2
(2700 2875);
DISPLAY 0.617021 (2700 2875);
PAINT SKYBLUE (2700 2875);
FORCEPROP 1 LAST PACK_TYPE 0402
J 1
(2800 2875);
DISPLAY 0.617021 (2800 2875);
PAINT SKYBLUE (2800 2875);
FORCEPROP 1 LAST VOLTAGE 16V
J 0
(2375 2875);
DISPLAY 0.617021 (2375 2875);
PAINT SKYBLUE (2375 2875);
FORCEPROP 1 LAST VALUE 0.22UF
J 2
(2225 2875);
DISPLAY 0.617021 (2225 2875);
PAINT SKYBLUE (2225 2875);
FORCEPROP 1 LAST PART_NUMBER A36096-155
J 1
(2575 2925);
DISPLAY 0.617021 (2575 2925);
PAINT BLUE (2575 2925);
FORCEPROP 1 LAST PATH I86
J 0
(2275 3100);
DISPLAY 0.978723 (2275 3100);
PAINT WHITE (2275 3100);
DISPLAY INVISIBLE (2275 3100);
FORCEPROP 0 LAST CDS_SEC 1
J 0
(2275 3000);
PAINT MONO (2275 3000);
DISPLAY INVISIBLE (2275 3000);
FORCEPROP 2 LAST CDS_LOCATION C1F20
J 1
(2275 2975);
DISPLAY 0.617021 (2275 2975);
PAINT AQUA (2275 2975);
DISPLAY INVISIBLE (2275 2975);
FORCEPROP 2 LAST CDS_LIB mstr_discrete
J 0
(2275 2900);
PAINT ORANGE (2275 2900);
DISPLAY INVISIBLE (2275 2900);
FORCEPROP 0 LAST BOM_COST IO_SLOT
J 0
(2275 3050);
DISPLAY 1.021277 (2275 3050);
PAINT ORANGE (2275 3050);
DISPLAY INVISIBLE (2275 3050);
FORCEPROP 0 LAST ROOM IO_SLOT
J 0
(2275 3100);
DISPLAY 1.021277 (2275 3100);
PAINT ORANGE (2275 3100);
DISPLAY INVISIBLE (2275 3100);
FORCEPROP 2 LAST SEC_TYPE 0402
J 0
(2275 3150);
DISPLAY 1.021277 (2275 3150);
PAINT ORANGE (2275 3150);
DISPLAY INVISIBLE (2275 3150);
FORCEPROP 2 LAST SEC 1
J 0
(2275 3150);
DISPLAY 0.680851 (2275 3150);
PAINT MONO (2275 3150);
DISPLAY INVISIBLE (2275 3150);
FORCEADD CAP..2
(2275 3300);
FORCEPROP 1 LAST LOCATION C1F10
J 1
(2275 3325);
DISPLAY 0.617021 (2275 3325);
PAINT AQUA (2275 3325);
FORCEPROP 1 LAST MATERIAL X7R
J 0
(2500 3275);
DISPLAY 0.617021 (2500 3275);
PAINT SKYBLUE (2500 3275);
FORCEPROP 1 LAST TOLERANCE 10%
J 2
(2700 3275);
DISPLAY 0.617021 (2700 3275);
PAINT SKYBLUE (2700 3275);
FORCEPROP 1 LAST VALUE 0.22UF
J 2
(2225 3275);
DISPLAY 0.617021 (2225 3275);
PAINT SKYBLUE (2225 3275);
FORCEPROP 1 LASTPIN (2175 3300) $PN 1
J 0
(2165 3315);
DISPLAY 0.617021 (2165 3315);
PAINT ORANGE (2165 3315);
FORCEPROP 1 LAST VOLTAGE 16V
J 0
(2375 3275);
DISPLAY 0.617021 (2375 3275);
PAINT SKYBLUE (2375 3275);
FORCEPROP 1 LASTPIN (2375 3300) $PN 2
J 0
(2360 3315);
DISPLAY 0.617021 (2360 3315);
PAINT ORANGE (2360 3315);
FORCEPROP 1 LAST PACK_TYPE 0402
J 1
(2800 3275);
DISPLAY 0.617021 (2800 3275);
PAINT SKYBLUE (2800 3275);
FORCEPROP 1 LAST PART_NUMBER A36096-155
J 1
(2550 3325);
DISPLAY 0.617021 (2550 3325);
PAINT BLUE (2550 3325);
FORCEPROP 1 LAST PATH I87
J 0
(2275 3500);
DISPLAY 0.978723 (2275 3500);
PAINT WHITE (2275 3500);
DISPLAY INVISIBLE (2275 3500);
FORCEPROP 0 LAST CDS_SEC 1
J 0
(2550 3375);
PAINT MONO (2550 3375);
DISPLAY INVISIBLE (2550 3375);
FORCEPROP 2 LAST CDS_LIB mstr_discrete
J 0
(2275 3300);
PAINT ORANGE (2275 3300);
DISPLAY INVISIBLE (2275 3300);
FORCEPROP 2 LAST CDS_LOCATION C1F10
J 1
(2275 3400);
DISPLAY 0.617021 (2275 3400);
PAINT AQUA (2275 3400);
DISPLAY INVISIBLE (2275 3400);
FORCEPROP 0 LAST BOM_COST IO_SLOT
J 0
(2275 3450);
DISPLAY 1.021277 (2275 3450);
PAINT ORANGE (2275 3450);
DISPLAY INVISIBLE (2275 3450);
FORCEPROP 0 LAST ROOM IO_SLOT
J 0
(2275 3500);
DISPLAY 1.021277 (2275 3500);
PAINT ORANGE (2275 3500);
DISPLAY INVISIBLE (2275 3500);
FORCEPROP 2 LAST SEC 1
J 0
(2275 3550);
DISPLAY 0.680851 (2275 3550);
PAINT MONO (2275 3550);
DISPLAY INVISIBLE (2275 3550);
FORCEPROP 2 LAST SEC_TYPE 0402
J 0
(2275 3550);
DISPLAY 1.021277 (2275 3550);
PAINT ORANGE (2275 3550);
DISPLAY INVISIBLE (2275 3550);
FORCEADD CAP..2
(2275 3150);
FORCEPROP 1 LAST VOLTAGE 16V
J 0
(2375 3125);
DISPLAY 0.617021 (2375 3125);
PAINT SKYBLUE (2375 3125);
FORCEPROP 1 LAST PART_NUMBER A36096-155
J 1
(2575 3175);
DISPLAY 0.617021 (2575 3175);
PAINT BLUE (2575 3175);
FORCEPROP 1 LASTPIN (2375 3150) $PN 2
J 0
(2360 3165);
DISPLAY 0.617021 (2360 3165);
PAINT ORANGE (2360 3165);
FORCEPROP 1 LAST LOCATION C1F6
J 1
(2275 3175);
DISPLAY 0.617021 (2275 3175);
PAINT AQUA (2275 3175);
FORCEPROP 1 LAST VALUE 0.22UF
J 2
(2225 3125);
DISPLAY 0.617021 (2225 3125);
PAINT SKYBLUE (2225 3125);
FORCEPROP 1 LASTPIN (2175 3150) $PN 1
J 0
(2165 3165);
DISPLAY 0.617021 (2165 3165);
PAINT ORANGE (2165 3165);
FORCEPROP 1 LAST MATERIAL X7R
J 0
(2500 3125);
DISPLAY 0.617021 (2500 3125);
PAINT SKYBLUE (2500 3125);
FORCEPROP 1 LAST PACK_TYPE 0402
J 1
(2800 3125);
DISPLAY 0.617021 (2800 3125);
PAINT SKYBLUE (2800 3125);
FORCEPROP 1 LAST TOLERANCE 10%
J 2
(2700 3125);
DISPLAY 0.617021 (2700 3125);
PAINT SKYBLUE (2700 3125);
FORCEPROP 1 LAST PATH I88
J 0
(2275 3350);
DISPLAY 0.978723 (2275 3350);
PAINT WHITE (2275 3350);
DISPLAY INVISIBLE (2275 3350);
FORCEPROP 0 LAST CDS_SEC 1
J 0
(2575 3225);
PAINT MONO (2575 3225);
DISPLAY INVISIBLE (2575 3225);
FORCEPROP 2 LAST CDS_LIB mstr_discrete
J 0
(2275 3150);
PAINT ORANGE (2275 3150);
DISPLAY INVISIBLE (2275 3150);
FORCEPROP 2 LAST CDS_LOCATION C1F6
J 1
(2275 3250);
DISPLAY 0.617021 (2275 3250);
PAINT AQUA (2275 3250);
DISPLAY INVISIBLE (2275 3250);
FORCEPROP 0 LAST BOM_COST IO_SLOT
J 0
(2275 3300);
DISPLAY 1.021277 (2275 3300);
PAINT ORANGE (2275 3300);
DISPLAY INVISIBLE (2275 3300);
FORCEPROP 0 LAST ROOM IO_SLOT
J 0
(2275 3350);
DISPLAY 1.021277 (2275 3350);
PAINT ORANGE (2275 3350);
DISPLAY INVISIBLE (2275 3350);
FORCEPROP 2 LAST SEC_TYPE 0402
J 0
(2275 3400);
DISPLAY 1.021277 (2275 3400);
PAINT ORANGE (2275 3400);
DISPLAY INVISIBLE (2275 3400);
FORCEPROP 2 LAST SEC 1
J 0
(2275 3400);
DISPLAY 0.680851 (2275 3400);
PAINT MONO (2275 3400);
DISPLAY INVISIBLE (2275 3400);
FORCEADD CAP..2
(2250 3450);
FORCEPROP 1 LAST LOCATION C1F13
J 1
(2250 3500);
DISPLAY 0.617021 (2250 3500);
PAINT AQUA (2250 3500);
FORCEPROP 1 LAST VOLTAGE 16V
J 0
(2350 3425);
DISPLAY 0.617021 (2350 3425);
PAINT SKYBLUE (2350 3425);
FORCEPROP 1 LAST MATERIAL X7R
J 0
(2475 3425);
DISPLAY 0.617021 (2475 3425);
PAINT SKYBLUE (2475 3425);
FORCEPROP 1 LASTPIN (2150 3450) $PN 1
J 0
(2140 3465);
DISPLAY 0.617021 (2140 3465);
PAINT ORANGE (2140 3465);
FORCEPROP 1 LAST VALUE 0.22UF
J 2
(2200 3425);
DISPLAY 0.617021 (2200 3425);
PAINT SKYBLUE (2200 3425);
FORCEPROP 1 LAST TOLERANCE 10%
J 2
(2675 3425);
DISPLAY 0.617021 (2675 3425);
PAINT SKYBLUE (2675 3425);
FORCEPROP 1 LAST PACK_TYPE 0402
J 1
(2775 3425);
DISPLAY 0.617021 (2775 3425);
PAINT SKYBLUE (2775 3425);
FORCEPROP 1 LASTPIN (2350 3450) $PN 2
J 0
(2335 3465);
DISPLAY 0.617021 (2335 3465);
PAINT ORANGE (2335 3465);
FORCEPROP 1 LAST PART_NUMBER A36096-155
J 1
(2525 3475);
DISPLAY 0.617021 (2525 3475);
PAINT BLUE (2525 3475);
FORCEPROP 1 LAST PATH I89
J 0
(2250 3650);
DISPLAY 0.978723 (2250 3650);
PAINT WHITE (2250 3650);
DISPLAY INVISIBLE (2250 3650);
FORCEPROP 0 LAST CDS_SEC 1
J 0
(2250 3550);
PAINT MONO (2250 3550);
DISPLAY INVISIBLE (2250 3550);
FORCEPROP 2 LAST CDS_LIB mstr_discrete
J 0
(2250 3450);
PAINT ORANGE (2250 3450);
DISPLAY INVISIBLE (2250 3450);
FORCEPROP 2 LAST CDS_LOCATION C1F13
J 1
(2250 3550);
DISPLAY 0.617021 (2250 3550);
PAINT AQUA (2250 3550);
DISPLAY INVISIBLE (2250 3550);
FORCEPROP 0 LAST ROOM IO_SLOT
J 0
(2250 3650);
DISPLAY 1.021277 (2250 3650);
PAINT ORANGE (2250 3650);
DISPLAY INVISIBLE (2250 3650);
FORCEPROP 0 LAST BOM_COST IO_SLOT
J 0
(2250 3600);
DISPLAY 1.021277 (2250 3600);
PAINT ORANGE (2250 3600);
DISPLAY INVISIBLE (2250 3600);
FORCEPROP 2 LAST SEC_TYPE 0402
J 0
(2250 3700);
DISPLAY 1.021277 (2250 3700);
PAINT ORANGE (2250 3700);
DISPLAY INVISIBLE (2250 3700);
FORCEPROP 2 LAST SEC 1
J 0
(2250 3700);
DISPLAY 0.680851 (2250 3700);
PAINT MONO (2250 3700);
DISPLAY INVISIBLE (2250 3700);
FORCEADD OFFPAGE..1
(-2875 2325);
FORCEPROP 2 LAST $XR0 182 
J 0
(-3157 2325);
DISPLAY 0.638298 (-3157 2325);
PAINT MONO (-3157 2325);
FORCEPROP 2 LAST PATH I9
J 0
(-3150 2375);
DISPLAY 1.021277 (-3150 2375);
PAINT ORANGE (-3150 2375);
DISPLAY INVISIBLE (-3150 2375);
FORCEPROP 2 LAST CDS_LIB mstr_standard
J 0
(-2875 2325);
PAINT ORANGE (-2875 2325);
DISPLAY INVISIBLE (-2875 2325);
FORCEPROP 1 LAST OFFPAGE TRUE
J 0
(-2550 2200);
DISPLAY 0.872340 (-2550 2200);
PAINT GREEN (-2550 2200);
DISPLAY INVISIBLE (-2550 2200);
FORCEPROP 1 LAST COMMENT_BODY TRUE
J 0
(-2750 2225);
DISPLAY 0.872340 (-2750 2225);
PAINT GREEN (-2750 2225);
DISPLAY INVISIBLE (-2750 2225);
FORCEADD CAP..2
(2250 3650);
FORCEPROP 1 LAST PART_NUMBER A36096-155
J 1
(2525 3675);
DISPLAY 0.617021 (2525 3675);
PAINT BLUE (2525 3675);
FORCEPROP 1 LAST VOLTAGE 16V
J 0
(2350 3625);
DISPLAY 0.617021 (2350 3625);
PAINT SKYBLUE (2350 3625);
FORCEPROP 1 LAST MATERIAL X7R
J 0
(2475 3625);
DISPLAY 0.617021 (2475 3625);
PAINT SKYBLUE (2475 3625);
FORCEPROP 1 LASTPIN (2350 3650) $PN 2
J 0
(2335 3665);
DISPLAY 0.617021 (2335 3665);
PAINT ORANGE (2335 3665);
FORCEPROP 1 LAST LOCATION C1F2
J 1
(2250 3675);
DISPLAY 0.617021 (2250 3675);
PAINT AQUA (2250 3675);
FORCEPROP 1 LAST VALUE 0.22UF
J 2
(2200 3625);
DISPLAY 0.617021 (2200 3625);
PAINT SKYBLUE (2200 3625);
FORCEPROP 1 LAST PACK_TYPE 0402
J 1
(2775 3625);
DISPLAY 0.617021 (2775 3625);
PAINT SKYBLUE (2775 3625);
FORCEPROP 1 LAST TOLERANCE 10%
J 2
(2675 3625);
DISPLAY 0.617021 (2675 3625);
PAINT SKYBLUE (2675 3625);
FORCEPROP 1 LASTPIN (2150 3650) $PN 1
J 0
(2140 3665);
DISPLAY 0.617021 (2140 3665);
PAINT ORANGE (2140 3665);
FORCEPROP 1 LAST PATH I90
J 0
(2250 3850);
DISPLAY 0.978723 (2250 3850);
PAINT WHITE (2250 3850);
DISPLAY INVISIBLE (2250 3850);
FORCEPROP 0 LAST CDS_SEC 1
J 0
(2525 3725);
PAINT MONO (2525 3725);
DISPLAY INVISIBLE (2525 3725);
FORCEPROP 2 LAST CDS_LIB mstr_discrete
J 0
(2250 3650);
PAINT ORANGE (2250 3650);
DISPLAY INVISIBLE (2250 3650);
FORCEPROP 2 LAST CDS_LOCATION C1F2
J 1
(2250 3750);
DISPLAY 0.617021 (2250 3750);
PAINT AQUA (2250 3750);
DISPLAY INVISIBLE (2250 3750);
FORCEPROP 0 LAST BOM_COST IO_SLOT
J 0
(2250 3800);
DISPLAY 1.021277 (2250 3800);
PAINT ORANGE (2250 3800);
DISPLAY INVISIBLE (2250 3800);
FORCEPROP 0 LAST ROOM IO_SLOT
J 0
(2250 3850);
DISPLAY 1.021277 (2250 3850);
PAINT ORANGE (2250 3850);
DISPLAY INVISIBLE (2250 3850);
FORCEPROP 2 LAST SEC_TYPE 0402
J 0
(2250 3900);
DISPLAY 1.021277 (2250 3900);
PAINT ORANGE (2250 3900);
DISPLAY INVISIBLE (2250 3900);
FORCEPROP 2 LAST SEC 1
J 0
(2250 3900);
DISPLAY 0.680851 (2250 3900);
PAINT MONO (2250 3900);
DISPLAY INVISIBLE (2250 3900);
FORCEADD CAP..2
(2250 3800);
FORCEPROP 1 LAST LOCATION C1F4
J 1
(2250 3850);
DISPLAY 0.617021 (2250 3850);
PAINT AQUA (2250 3850);
FORCEPROP 1 LASTPIN (2150 3800) $PN 1
J 0
(2140 3815);
DISPLAY 0.617021 (2140 3815);
PAINT ORANGE (2140 3815);
FORCEPROP 1 LAST VOLTAGE 16V
J 0
(2350 3775);
DISPLAY 0.617021 (2350 3775);
PAINT SKYBLUE (2350 3775);
FORCEPROP 1 LASTPIN (2350 3800) $PN 2
J 0
(2335 3815);
DISPLAY 0.617021 (2335 3815);
PAINT ORANGE (2335 3815);
FORCEPROP 1 LAST PACK_TYPE 0402
J 1
(2775 3775);
DISPLAY 0.617021 (2775 3775);
PAINT SKYBLUE (2775 3775);
FORCEPROP 1 LAST PART_NUMBER A36096-155
J 1
(2525 3825);
DISPLAY 0.617021 (2525 3825);
PAINT BLUE (2525 3825);
FORCEPROP 1 LAST TOLERANCE 10%
J 2
(2675 3775);
DISPLAY 0.617021 (2675 3775);
PAINT SKYBLUE (2675 3775);
FORCEPROP 1 LAST MATERIAL X7R
J 0
(2475 3775);
DISPLAY 0.617021 (2475 3775);
PAINT SKYBLUE (2475 3775);
FORCEPROP 1 LAST VALUE 0.22UF
J 2
(2200 3775);
DISPLAY 0.617021 (2200 3775);
PAINT SKYBLUE (2200 3775);
FORCEPROP 1 LAST PATH I91
J 0
(2250 4000);
DISPLAY 0.978723 (2250 4000);
PAINT WHITE (2250 4000);
DISPLAY INVISIBLE (2250 4000);
FORCEPROP 0 LAST CDS_SEC 1
J 0
(2250 3900);
PAINT MONO (2250 3900);
DISPLAY INVISIBLE (2250 3900);
FORCEPROP 2 LAST CDS_LIB mstr_discrete
J 0
(2250 3800);
PAINT ORANGE (2250 3800);
DISPLAY INVISIBLE (2250 3800);
FORCEPROP 2 LAST CDS_LOCATION C1F4
J 1
(2250 3850);
DISPLAY 0.617021 (2250 3850);
PAINT AQUA (2250 3850);
DISPLAY INVISIBLE (2250 3850);
FORCEPROP 0 LAST BOM_COST IO_SLOT
J 0
(2250 3950);
DISPLAY 1.021277 (2250 3950);
PAINT ORANGE (2250 3950);
DISPLAY INVISIBLE (2250 3950);
FORCEPROP 0 LAST ROOM IO_SLOT
J 0
(2250 4000);
DISPLAY 1.021277 (2250 4000);
PAINT ORANGE (2250 4000);
DISPLAY INVISIBLE (2250 4000);
FORCEPROP 2 LAST SEC_TYPE 0402
J 0
(2250 4050);
DISPLAY 1.021277 (2250 4050);
PAINT ORANGE (2250 4050);
DISPLAY INVISIBLE (2250 4050);
FORCEPROP 2 LAST SEC 1
J 0
(2250 4050);
DISPLAY 0.680851 (2250 4050);
PAINT MONO (2250 4050);
DISPLAY INVISIBLE (2250 4050);
FORCEADD TAP..6
R 2
(2925 3150);
FORCEPROP 3 LASTPIN (2875 3150) SIG_NAME P3E_CPU1_PE3_MP_TXP<5>
J 0
(2885 3160);
DISPLAY 0.659574 (2885 3160);
PAINT MONO (2885 3160);
DISPLAY INVISIBLE (2885 3160);
FORCEPROP 1 LASTPIN (2875 3150) BN 5
J 2
(2927 3158);
DISPLAY 0.617021 (2927 3158);
PAINT GREEN (2927 3158);
FORCEPROP 1 LAST PATH I92
J 2
(2927 3150);
DISPLAY 0.872340 (2927 3150);
PAINT GREEN (2927 3150);
DISPLAY INVISIBLE (2927 3150);
FORCEPROP 2 LAST CDS_LIB mstr_standard
J 0
(2925 3150);
PAINT ORANGE (2925 3150);
DISPLAY INVISIBLE (2925 3150);
FORCEPROP 1 LAST BODY_TYPE PLUMBING
J 2
(2925 3100);
DISPLAY 1.234043 (2925 3100);
PAINT GREEN (2925 3100);
DISPLAY INVISIBLE (2925 3100);
FORCEPROP 1 LAST HDL_TAP TRUE
J 2
(2600 3025);
DISPLAY 1.234043 (2600 3025);
PAINT GREEN (2600 3025);
DISPLAY INVISIBLE (2600 3025);
FORCEADD TAP..6
R 2
(2925 3250);
FORCEPROP 3 LASTPIN (2875 3250) SIG_NAME P3E_CPU1_PE3_MP_TXP<4>
J 0
(2885 3260);
DISPLAY 0.659574 (2885 3260);
PAINT MONO (2885 3260);
DISPLAY INVISIBLE (2885 3260);
FORCEPROP 1 LASTPIN (2875 3250) BN 4
J 2
(2927 3258);
DISPLAY 0.617021 (2927 3258);
PAINT GREEN (2927 3258);
FORCEPROP 1 LAST PATH I93
J 2
(2927 3250);
DISPLAY 0.872340 (2927 3250);
PAINT GREEN (2927 3250);
DISPLAY INVISIBLE (2927 3250);
FORCEPROP 2 LAST CDS_LIB mstr_standard
J 0
(2925 3250);
PAINT ORANGE (2925 3250);
DISPLAY INVISIBLE (2925 3250);
FORCEPROP 1 LAST BODY_TYPE PLUMBING
J 2
(2925 3200);
DISPLAY 1.234043 (2925 3200);
PAINT GREEN (2925 3200);
DISPLAY INVISIBLE (2925 3200);
FORCEPROP 1 LAST HDL_TAP TRUE
J 2
(2600 3125);
DISPLAY 1.234043 (2600 3125);
PAINT GREEN (2600 3125);
DISPLAY INVISIBLE (2600 3125);
FORCEADD TAP..6
R 2
(2925 2850);
FORCEPROP 3 LASTPIN (2875 2850) SIG_NAME P3E_CPU1_PE3_MP_TXP<0>
J 0
(2885 2860);
DISPLAY 0.659574 (2885 2860);
PAINT MONO (2885 2860);
DISPLAY INVISIBLE (2885 2860);
FORCEPROP 1 LASTPIN (2875 2850) BN 0
J 2
(2927 2858);
DISPLAY 0.617021 (2927 2858);
PAINT GREEN (2927 2858);
FORCEPROP 1 LAST PATH I94
J 2
(2927 2850);
DISPLAY 0.872340 (2927 2850);
PAINT GREEN (2927 2850);
DISPLAY INVISIBLE (2927 2850);
FORCEPROP 2 LAST CDS_LIB mstr_standard
J 0
(2925 2850);
PAINT ORANGE (2925 2850);
DISPLAY INVISIBLE (2925 2850);
FORCEPROP 1 LAST BODY_TYPE PLUMBING
J 2
(2925 2800);
DISPLAY 1.234043 (2925 2800);
PAINT GREEN (2925 2800);
DISPLAY INVISIBLE (2925 2800);
FORCEPROP 1 LAST HDL_TAP TRUE
J 2
(2600 2725);
DISPLAY 1.234043 (2600 2725);
PAINT GREEN (2600 2725);
DISPLAY INVISIBLE (2600 2725);
FORCEADD TAP..6
R 2
(2925 3650);
FORCEPROP 3 LASTPIN (2875 3650) SIG_NAME P3E_CPU1_PE3_MP_TXP<7>
J 0
(2885 3660);
DISPLAY 0.659574 (2885 3660);
PAINT MONO (2885 3660);
DISPLAY INVISIBLE (2885 3660);
FORCEPROP 1 LASTPIN (2875 3650) BN 7
J 2
(2927 3658);
DISPLAY 0.617021 (2927 3658);
PAINT GREEN (2927 3658);
FORCEPROP 1 LAST PATH I95
J 2
(2927 3650);
DISPLAY 0.872340 (2927 3650);
PAINT GREEN (2927 3650);
DISPLAY INVISIBLE (2927 3650);
FORCEPROP 2 LAST CDS_LIB mstr_standard
J 0
(2925 3650);
PAINT ORANGE (2925 3650);
DISPLAY INVISIBLE (2925 3650);
FORCEPROP 1 LAST BODY_TYPE PLUMBING
J 2
(2925 3600);
DISPLAY 1.234043 (2925 3600);
PAINT GREEN (2925 3600);
DISPLAY INVISIBLE (2925 3600);
FORCEPROP 1 LAST HDL_TAP TRUE
J 2
(2600 3525);
DISPLAY 1.234043 (2600 3525);
PAINT GREEN (2600 3525);
DISPLAY INVISIBLE (2600 3525);
FORCEADD TAP..6
R 2
(2925 3750);
FORCEPROP 3 LASTPIN (2875 3750) SIG_NAME P3E_CPU1_PE3_MP_TXP<6>
J 0
(2885 3760);
DISPLAY 0.659574 (2885 3760);
PAINT MONO (2885 3760);
DISPLAY INVISIBLE (2885 3760);
FORCEPROP 1 LASTPIN (2875 3750) BN 6
J 2
(2927 3758);
DISPLAY 0.617021 (2927 3758);
PAINT GREEN (2927 3758);
FORCEPROP 1 LAST PATH I96
J 2
(2927 3750);
DISPLAY 0.872340 (2927 3750);
PAINT GREEN (2927 3750);
DISPLAY INVISIBLE (2927 3750);
FORCEPROP 2 LAST CDS_LIB mstr_standard
J 0
(2925 3750);
PAINT ORANGE (2925 3750);
DISPLAY INVISIBLE (2925 3750);
FORCEPROP 1 LAST BODY_TYPE PLUMBING
J 2
(2925 3700);
DISPLAY 1.234043 (2925 3700);
PAINT GREEN (2925 3700);
DISPLAY INVISIBLE (2925 3700);
FORCEPROP 1 LAST HDL_TAP TRUE
J 2
(2600 3625);
DISPLAY 1.234043 (2600 3625);
PAINT GREEN (2600 3625);
DISPLAY INVISIBLE (2600 3625);
FORCEADD TAP..6
R 2
(2925 3400);
FORCEPROP 3 LASTPIN (2875 3400) SIG_NAME P3E_CPU1_PE3_MP_TXP<3>
J 0
(2885 3410);
DISPLAY 0.659574 (2885 3410);
PAINT MONO (2885 3410);
DISPLAY INVISIBLE (2885 3410);
FORCEPROP 1 LASTPIN (2875 3400) BN 3
J 2
(2927 3408);
DISPLAY 0.617021 (2927 3408);
PAINT GREEN (2927 3408);
FORCEPROP 1 LAST PATH I97
J 2
(2927 3400);
DISPLAY 0.872340 (2927 3400);
PAINT GREEN (2927 3400);
DISPLAY INVISIBLE (2927 3400);
FORCEPROP 2 LAST CDS_LIB mstr_standard
J 0
(2925 3400);
PAINT ORANGE (2925 3400);
DISPLAY INVISIBLE (2925 3400);
FORCEPROP 1 LAST BODY_TYPE PLUMBING
J 2
(2925 3350);
DISPLAY 1.234043 (2925 3350);
PAINT GREEN (2925 3350);
DISPLAY INVISIBLE (2925 3350);
FORCEPROP 1 LAST HDL_TAP TRUE
J 2
(2600 3275);
DISPLAY 1.234043 (2600 3275);
PAINT GREEN (2600 3275);
DISPLAY INVISIBLE (2600 3275);
FORCEADD OFFPAGE..1
(2900 1050);
FORCEPROP 2 LAST $XR4 199 
J 0
(2138 1050);
DISPLAY 0.638298 (2138 1050);
PAINT MONO (2138 1050);
FORCEPROP 2 LAST $XR3 247 
J 0
(2258 1050);
DISPLAY 0.638298 (2258 1050);
PAINT MONO (2258 1050);
FORCEPROP 2 LAST $XR2 181 
J 0
(2378 1050);
DISPLAY 0.638298 (2378 1050);
PAINT MONO (2378 1050);
FORCEPROP 2 LAST $XR1 159 
J 0
(2498 1050);
DISPLAY 0.638298 (2498 1050);
PAINT MONO (2498 1050);
FORCEPROP 2 LAST $XR0 138 
J 0
(2618 1050);
DISPLAY 0.638298 (2618 1050);
PAINT MONO (2618 1050);
FORCEPROP 2 LAST PATH I98
J 0
(2625 1100);
DISPLAY 1.021277 (2625 1100);
PAINT ORANGE (2625 1100);
DISPLAY INVISIBLE (2625 1100);
FORCEPROP 2 LAST CDS_LIB mstr_standard
J 0
(2900 1050);
PAINT ORANGE (2900 1050);
DISPLAY INVISIBLE (2900 1050);
FORCEPROP 1 LAST OFFPAGE TRUE
J 0
(3225 925);
DISPLAY 0.872340 (3225 925);
PAINT GREEN (3225 925);
DISPLAY INVISIBLE (3225 925);
FORCEPROP 1 LAST COMMENT_BODY TRUE
J 0
(3025 950);
DISPLAY 0.872340 (3025 950);
PAINT GREEN (3025 950);
DISPLAY INVISIBLE (3025 950);
FORCEADD OFFPAGE..5
(2875 1150);
FORCEPROP 2 LAST $XR1 199 
J 0
(2500 1150);
DISPLAY 0.638298 (2500 1150);
PAINT MONO (2500 1150);
FORCEPROP 2 LAST $XR0 181 
J 0
(2620 1150);
DISPLAY 0.638298 (2620 1150);
PAINT MONO (2620 1150);
FORCEPROP 2 LAST PATH I99
J 0
(2625 1200);
DISPLAY 1.021277 (2625 1200);
PAINT ORANGE (2625 1200);
DISPLAY INVISIBLE (2625 1200);
FORCEPROP 2 LAST CDS_LIB mstr_standard
J 0
(2875 1150);
PAINT ORANGE (2875 1150);
DISPLAY INVISIBLE (2875 1150);
FORCEPROP 1 LAST OFFPAGE TRUE
J 0
(3200 1025);
DISPLAY 0.872340 (3200 1025);
PAINT GREEN (3200 1025);
DISPLAY INVISIBLE (3200 1025);
FORCEPROP 1 LAST COMMENT_BODY TRUE
J 0
(2975 1075);
DISPLAY 0.872340 (2975 1075);
PAINT GREEN (2975 1075);
DISPLAY INVISIBLE (2975 1075);
FORCEADD CAD_NOTE..1
(-1100 950);
FORCEPROP 0 LAST L3 74LVC08A
J 2
(-875 675);
DISPLAY 1.021277 (-875 675);
PAINT ORANGE (-875 675);
FORCEPROP 0 LAST L1 PLACE 0.1UF CAP
J 2
(-875 825);
DISPLAY 1.021277 (-875 825);
PAINT ORANGE (-875 825);
FORCEPROP 0 LAST L2 NEXT TO VCC PIN OF
J 2
(-875 750);
DISPLAY 1.021277 (-875 750);
PAINT ORANGE (-875 750);
FORCEPROP 2 LAST CDS_LIB mstr_symbols
J 0
(-1100 950);
PAINT ORANGE (-1100 950);
DISPLAY INVISIBLE (-1100 950);
FORCEPROP 1 LAST COMMENT_BODY TRUE
J 0
(-1075 1050);
DISPLAY 0.978723 (-1075 1050);
PAINT ORANGE (-1075 1050);
DISPLAY INVISIBLE (-1075 1050);
FORCEADD CAD_NOTE..1
(-3225 4450);
FORCEPROP 0 LAST L1 USE SHARED PADS FOR RESISTORS ON FOLLOWING NETS:
J 0
(-3375 4325);
DISPLAY 0.638298 (-3375 4325);
PAINT ORANGE (-3375 4325);
FORCEPROP 0 LAST L3 SPA_MID_DBG_RX_R
J 0
(-3375 4225);
DISPLAY 0.638298 (-3375 4225);
PAINT ORANGE (-3375 4225);
FORCEPROP 0 LAST L2 SPA_MID_DBG_TX_R
J 0
(-3375 4275);
DISPLAY 0.638298 (-3375 4275);
PAINT ORANGE (-3375 4275);
FORCEPROP 2 LAST CDS_LIB mstr_symbols
J 0
(-3225 4450);
PAINT ORANGE (-3225 4450);
DISPLAY INVISIBLE (-3225 4450);
FORCEPROP 1 LAST COMMENT_BODY TRUE
J 0
(-3200 4550);
DISPLAY 0.978723 (-3200 4550);
PAINT ORANGE (-3200 4550);
DISPLAY INVISIBLE (-3200 4550);
FORCEADD DNS..2
(-1745 3170);
PAINT RED (-1745 3170);
FORCEPROP 2 LAST CDS_LIB mstr_misc
J 0
(-1745 3170);
PAINT ORANGE (-1745 3170);
DISPLAY INVISIBLE (-1745 3170);
FORCEPROP 1 LAST COMMENT_BODY TRUE
R 1
J 0
(-1670 2945);
DISPLAY 0.872340 (-1670 2945);
PAINT GREEN (-1670 2945);
DISPLAY INVISIBLE (-1670 2945);
FORCEADD CAD_NOTE..1
(1575 2325);
FORCEPROP 0 LAST L1 PLACE 0.22UF TX CAPS CLOSE
J 0
(1425 2175);
DISPLAY 0.808511 (1425 2175);
PAINT ORANGE (1425 2175);
FORCEPROP 0 LAST L2 TO CONNECTOR PIN
J 0
(1425 2125);
DISPLAY 0.808511 (1425 2125);
PAINT ORANGE (1425 2125);
FORCEPROP 2 LAST CDS_LIB mstr_symbols
J 0
(1575 2325);
PAINT MONO (1575 2325);
DISPLAY INVISIBLE (1575 2325);
FORCEPROP 1 LAST COMMENT_BODY TRUE
J 0
(1600 2425);
DISPLAY 0.978723 (1600 2425);
PAINT PEACH (1600 2425);
DISPLAY INVISIBLE (1600 2425);
FORCEADD DESIGN_NOTE..1
(-3175 4075);
FORCEPROP 0 LAST L5 CREEK, DEPOPULATE THESE RESISTORS.
J 0
(-3375 3750);
DISPLAY 0.638298 (-3375 3750);
PAINT ORANGE (-3375 3750);
FORCEPROP 0 LAST L1 SERIES RESISTORS ON FAN_TACH3, FAN_TACH2, FAN_TACH1
J 0
(-3375 3975);
DISPLAY 0.638298 (-3375 3975);
PAINT ORANGE (-3375 3975);
FORCEPROP 0 LAST L2 AND FAN_PWM_OUT_SYS0_R ARE USED FOR STEERING
J 0
(-3375 3900);
DISPLAY 0.638298 (-3375 3900);
PAINT ORANGE (-3375 3900);
FORCEPROP 0 LAST L4 WITH BULLDOG CREEK. WHEN USING WITH BULLDOG
J 0
(-3375 3800);
DISPLAY 0.638298 (-3375 3800);
PAINT ORANGE (-3375 3800);
FORCEPROP 0 LAST L3 NETS FROM AIRMAX B TO AIRMAX A FOR COMPATIBILITY
J 0
(-3375 3850);
DISPLAY 0.638298 (-3375 3850);
PAINT ORANGE (-3375 3850);
FORCEPROP 2 LAST CDS_LIB mstr_symbols
J 0
(-3175 4075);
PAINT ORANGE (-3175 4075);
DISPLAY INVISIBLE (-3175 4075);
FORCEPROP 1 LAST COMMENT_BODY TRUE
J 0
(-3150 4175);
DISPLAY 0.978723 (-3150 4175);
PAINT ORANGE (-3150 4175);
DISPLAY INVISIBLE (-3150 4175);
FORCEADD DNS..2
(305 620);
PAINT RED (305 620);
FORCEPROP 2 LAST CDS_LIB mstr_misc
J 0
(305 620);
PAINT ORANGE (305 620);
DISPLAY INVISIBLE (305 620);
FORCEPROP 1 LAST COMMENT_BODY TRUE
R 1
J 0
(380 395);
DISPLAY 0.872340 (380 395);
PAINT GREEN (380 395);
DISPLAY INVISIBLE (380 395);
FORCEADD INTEL_CORP_BPAGE..1
(4500 50);
FORCEPROP 1 LAST CDS_CON_LAST_MODIFIED Fri Jun 16 17:49:07 2017
J 0
(3075 375);
PAINT ORANGE (3075 375);
DISPLAY INVISIBLE (3075 375);
FORCEPROP 1 LAST CUSTOM_TXT_CDS <CURRENT_DESIGN_SHEET> OF <TOTAL_DESIGN_SHEETS>
J 0
(4000 75);
PAINT ORANGE (4000 75);
FORCEPROP 1 LAST CUSTOM_TXT_CDS <CON_LAST_MODIFIED>
J 0
(500 150);
PAINT ORANGE (500 150);
FORCEPROP 2 LAST CUSTOM_TXT_CDS <XR_PAGE_TITLE>
J 0
(-3390 5300);
DISPLAY 0.638298 (-3390 5300);
PAINT PINK (-3390 5300);
DISPLAY INVISIBLE (-3390 5300);
FORCEPROP 1 LAST SCH_TITLE AIRMAX 1X8 MID-PLANE CONNECTOR A
J 0
(-3450 100);
DISPLAY 1.212766 (-3450 100);
PAINT ORANGE (-3450 100);
FORCEPROP 2 LAST PAGE_BORDER TRUE
J 0
(-3390 5300);
DISPLAY 0.638298 (-3390 5300);
PAINT PINK (-3390 5300);
DISPLAY INVISIBLE (-3390 5300);
FORCEPROP 2 LAST CDS_LIB mstr_symbols
J 0
(4500 50);
PAINT MONO (4500 50);
DISPLAY INVISIBLE (4500 50);
FORCEPROP 1 LAST COMMENT_BODY TRUE
J 0
(4512 62);
DISPLAY 0.468085 (4512 62);
PAINT GREEN (4512 62);
DISPLAY INVISIBLE (4512 62);
FORCEPROP 2 LAST CDS_XR_PAGE_TITLE CR-181 : @BASEBOARD_FAB2_LIB.BASEBOARD_FAB2(SCH_1):PAGE181
J 0
(-3390 5300);
DISPLAY 0.638298 (-3390 5300);
PAINT PINK (-3390 5300);
DISPLAY INVISIBLE (-3390 5300);
FORCEADD DNS..2
(-2120 3095);
PAINT RED (-2120 3095);
FORCEPROP 2 LAST CDS_LIB mstr_misc
J 0
(-2120 3095);
PAINT ORANGE (-2120 3095);
DISPLAY INVISIBLE (-2120 3095);
FORCEPROP 1 LAST COMMENT_BODY TRUE
R 1
J 0
(-2045 2870);
DISPLAY 0.872340 (-2045 2870);
PAINT GREEN (-2045 2870);
DISPLAY INVISIBLE (-2045 2870);
WIRE 16 -1 (3650 850)(3650 1000);
WIRE 16 -1 (3650 1000)(3900 1000);
WIRE 16 -1 (3650 1550)(3650 1350);
WIRE 16 -1 (3900 1350)(3650 1350);
WIRE 16 -1 (-2200 1200)(-2200 1175);
WIRE 16 -1 (-2200 1850)(-2200 1925);
WIRE 16 -1 (-700 550)(-700 700);
WIRE 16 -1 (-700 1050)(-700 900);
WIRE 16 -1 (300 525)(300 500);
WIRE 16 -1 (-750 2500)(-750 2450);
WIRE 16 -1 (-750 2650)(-750 2500);
WIRE 16 -1 (-750 2500)(-525 2500);
WIRE 16 -1 (-750 2650)(-750 3200);
WIRE 16 -1 (-750 2650)(-525 2650);
WIRE 16 -1 (-750 3350)(-750 3200);
WIRE 16 -1 (-750 3200)(-525 3200);
WIRE 16 -1 (-750 3550)(-750 3350);
WIRE 16 -1 (-750 3350)(-525 3350);
WIRE 16 -1 (-750 3700)(-750 3550);
WIRE 16 -1 (-525 3550)(-750 3550);
WIRE 16 -1 (-750 3850)(-750 3700);
WIRE 16 -1 (-750 3700)(-525 3700);
WIRE 16 -1 (-750 4000)(-750 3850);
WIRE 16 -1 (-750 3850)(-525 3850);
WIRE 16 -1 (-750 4100)(-750 4000);
WIRE 16 -1 (-750 4000)(-525 4000);
WIRE 16 -1 (-750 4250)(-750 4100);
WIRE 16 -1 (-750 4100)(-525 4100);
WIRE 16 -1 (-750 4400)(-750 4250);
WIRE 16 -1 (-750 4250)(-525 4250);
WIRE 16 -1 (-525 4400)(-750 4400);
WIRE 16 -1 (700 1450)(700 1325);
WIRE 16 -1 (1150 1450)(1150 1300);
WIRE 16 -1 (900 2450)(900 2500);
WIRE 16 -1 (900 2500)(900 2650);
WIRE 16 -1 (900 2500)(725 2500);
WIRE 16 -1 (900 2650)(900 2800);
WIRE 16 -1 (900 2650)(725 2650);
WIRE 16 -1 (900 2800)(900 2950);
WIRE 16 -1 (900 2800)(725 2800);
WIRE 16 -1 (900 2950)(900 3050);
WIRE 16 -1 (900 2950)(725 2950);
WIRE 16 -1 (900 3050)(900 3200);
WIRE 16 -1 (900 3050)(725 3050);
WIRE 16 -1 (900 3200)(900 3350);
WIRE 16 -1 (900 3200)(725 3200);
WIRE 16 -1 (900 3350)(900 3550);
WIRE 16 -1 (900 3350)(725 3350);
WIRE 16 -1 (900 3550)(900 3700);
WIRE 16 -1 (900 3550)(725 3550);
WIRE 16 -1 (900 3700)(900 3850);
WIRE 16 -1 (900 3700)(725 3700);
WIRE 16 -1 (900 3850)(900 4400);
WIRE 16 -1 (900 3850)(725 3850);
WIRE 16 -1 (900 4400)(725 4400);
WIRE 16 -1 (1050 2050)(1050 2000);
WIRE 16 -1 (2325 2325)(2325 2225);
WIRE 16 -1 (2325 2225)(2325 2050);
WIRE 16 -1 (2325 2225)(2550 2225);
WIRE 16 -1 (2325 2050)(2325 1875);
WIRE 16 -1 (2325 2050)(2550 2050);
WIRE 16 -1 (2325 1875)(2550 1875);
WIRE 17 -1 (2975 2725)(2975 2575);
WIRE 17 -1 (2975 2875)(2975 2725);
WIRE 17 -1 (4000 4575)(2975 4575);
FORCEPROP 2 LAST SIG_NAME P3E_CPU1_PE3_MP_TXP<7:0>
J 0
(3290 4585);
DISPLAY 0.617021 (3290 4585);
PAINT ORANGE (3290 4585);
WIRE 17 -1 (2975 3175)(2975 2875);
WIRE 17 -1 (2975 3275)(2975 3175);
WIRE 17 -1 (2975 4575)(2975 3775);
WIRE 17 -1 (2975 3675)(2975 3775);
WIRE 17 -1 (2975 3425)(2975 3275);
WIRE 17 -1 (2975 3425)(2975 3675);
WIRE 17 -1 (3225 2775)(3225 2625);
WIRE 17 -1 (3225 2925)(3225 2775);
WIRE 17 -1 (3225 3125)(3225 2925);
WIRE 17 -1 (3225 3325)(3225 3125);
WIRE 17 -1 (3225 3475)(3225 3325);
WIRE 17 -1 (3225 3475)(3225 3625);
WIRE 17 -1 (4000 4475)(3225 4475);
FORCEPROP 2 LAST SIG_NAME P3E_CPU1_PE3_MP_TXN<7:0>
J 0
(3290 4485);
DISPLAY 0.617021 (3290 4485);
PAINT ORANGE (3290 4485);
WIRE 17 -1 (3225 3625)(3225 3825);
WIRE 17 -1 (3225 3825)(3225 4475);
WIRE 17 -1 (-1300 4700)(-2825 4700);
FORCEPROP 2 LAST SIG_NAME P3E_CPU1_PE3_MP_RXN<7:0>
J 0
(-2810 4710);
DISPLAY 0.617021 (-2810 4710);
PAINT ORANGE (-2810 4710);
WIRE 17 -1 (-1300 4700)(-1300 4525);
WIRE 17 -1 (-1300 3425)(-1300 3325);
WIRE 17 -1 (-1300 4525)(-1300 4375);
WIRE 17 -1 (-1300 4175)(-1300 4375);
WIRE 17 -1 (-1300 3625)(-1300 3425);
WIRE 17 -1 (-1300 3825)(-1300 3625);
WIRE 17 -1 (-1300 3975)(-1300 4175);
WIRE 17 -1 (-1300 3975)(-1300 3825);
WIRE 17 -1 (-1050 3475)(-1050 3275);
WIRE 17 -1 (-1050 4825)(-2825 4825);
FORCEPROP 2 LAST SIG_NAME P3E_CPU1_PE3_MP_RXP<7:0>
J 0
(-2810 4835);
DISPLAY 0.617021 (-2810 4835);
PAINT ORANGE (-2810 4835);
WIRE 17 -1 (-1050 4825)(-1050 4475);
WIRE 17 -1 (-1050 3675)(-1050 3475);
WIRE 17 -1 (-1050 3775)(-1050 3675);
WIRE 17 -1 (-1050 4475)(-1050 4325);
WIRE 17 -1 (-1050 4225)(-1050 4325);
WIRE 17 -1 (-1050 3925)(-1050 3775);
WIRE 17 -1 (-1050 3925)(-1050 4225);
WIRE 16 -1 (3900 1100)(2950 1100);
FORCEPROP 0 LAST SIG_NAME SMB_BMC_PMBUS_STBY_LVC3_SDA
J 0
(2965 1110);
DISPLAY 0.617021 (2965 1110);
PAINT ORANGE (2965 1110);
WIRE 16 -1 (2950 1050)(3900 1050);
FORCEPROP 0 LAST SIG_NAME SMB_BMC_PMBUS_STBY_LVC3_SCL
J 0
(2965 1060);
DISPLAY 0.617021 (2965 1060);
PAINT ORANGE (2965 1060);
WIRE 3 2175 (-2750 1500)(-1750 1500);
WIRE 3 2175 (-1750 1500)(-1750 800);
WIRE 3 2175 (-2750 1500)(-2750 800);
WIRE 3 2175 (-2750 800)(-1750 800);
WIRE 16 -1 (-2200 1550)(-2200 1400);
WIRE 16 -1 (-2200 1650)(-2200 1550);
WIRE 16 -1 (-1650 1550)(-2200 1550);
WIRE 16 -1 (-2800 1550)(-2200 1550);
FORCEPROP 0 LAST SIG_NAME FM_MATED_IN_N
J 0
(-2710 1560);
DISPLAY 0.617021 (-2710 1560);
PAINT ORANGE (-2710 1560);
WIRE 3 682 (-450 4800)(-450 2150);
WIRE 3 682 (650 4800)(-450 4800);
WIRE 3 682 (-450 2150)(650 2150);
WIRE 3 682 (650 2150)(650 4800);
WIRE 16 -1 (2950 1250)(3900 1250);
FORCEPROP 2 LAST SIG_NAME FM_MP_PS_FAIL_N
J 0
(2950 1260);
DISPLAY 0.617021 (2950 1260);
PAINT ORANGE (2950 1260);
WIRE 16 -1 (3900 1150)(2925 1150);
FORCEPROP 0 LAST SIG_NAME IRQ_SML1_PMBUS_ALERT_R_N
J 0
(2965 1160);
DISPLAY 0.617021 (2965 1160);
PAINT ORANGE (2965 1160);
WIRE 16 -1 (3900 1200)(2950 1200);
FORCEPROP 0 LAST SIG_NAME FM_MATED_IN_N
J 0
(2950 1210);
DISPLAY 0.617021 (2950 1210);
PAINT ORANGE (2950 1210);
WIRE 16 -1 (3225 2050)(2750 2050);
FORCEPROP 0 LAST SIG_NAME FM_MB_SLOT_ID1
J 0
(2915 2060);
DISPLAY 0.617021 (2915 2060);
PAINT ORANGE (2915 2060);
WIRE 16 -1 (-2125 2800)(-975 2800);
WIRE 16 -1 (-975 2800)(-525 2800);
WIRE 16 -1 (-975 2225)(-975 2800);
WIRE 16 -1 (-2825 2225)(-975 2225);
FORCEPROP 2 LAST SIG_NAME FAN_TACH0_R
J 0
(-2710 2235);
DISPLAY 0.617021 (-2710 2235);
PAINT ORANGE (-2710 2235);
WIRE 16 -1 (-2125 2900)(-1075 2900);
WIRE 16 -1 (-1075 2900)(-525 2900);
WIRE 16 -1 (-1075 2325)(-1075 2900);
WIRE 16 -1 (-2825 2325)(-1075 2325);
FORCEPROP 2 LAST SIG_NAME FAN_TACH2_R
J 0
(-2710 2335);
DISPLAY 0.617021 (-2710 2335);
PAINT ORANGE (-2710 2335);
WIRE 16 -1 (-1425 2950)(-1125 2950);
WIRE 16 -1 (-1125 2950)(-525 2950);
WIRE 16 -1 (-1125 2375)(-1125 2950);
WIRE 16 -1 (-2825 2375)(-1125 2375);
FORCEPROP 2 LAST SIG_NAME FAN_TACH3_R
J 0
(-2710 2385);
DISPLAY 0.617021 (-2710 2385);
PAINT ORANGE (-2710 2385);
WIRE 16 -1 (-1025 2850)(-1425 2850);
WIRE 16 -1 (-525 2850)(-1025 2850);
WIRE 16 -1 (-1025 2275)(-1025 2850);
WIRE 16 -1 (-2825 2275)(-1025 2275);
FORCEPROP 2 LAST SIG_NAME FAN_TACH1_R
J 0
(-2710 2285);
DISPLAY 0.617021 (-2710 2285);
PAINT ORANGE (-2710 2285);
WIRE 16 -1 (-1450 1550)(-525 1550);
FORCEPROP 0 LAST SIG_NAME FM_MATED_IN_D1_N
J 0
(-1110 1560);
DISPLAY 0.617021 (-1110 1560);
PAINT ORANGE (-1110 1560);
FORCEPROP 2 LASTPROP $XRERR UNIQUE?
J 0
(-1350 1560);
DISPLAY 0.638298 (-1350 1560);
PAINT MONO (-1350 1560);
DISPLAY INVISIBLE (-1350 1560);
WIRE 16 -1 (-325 1550)(550 1550);
FORCEPROP 0 LAST SIG_NAME FM_MATED_IN_D2_N
J 0
(-160 1560);
DISPLAY 0.617021 (-160 1560);
PAINT ORANGE (-160 1560);
FORCEPROP 2 LASTPROP $XRERR UNIQUE?
J 0
(-400 1560);
DISPLAY 0.638298 (-400 1560);
PAINT MONO (-400 1560);
DISPLAY INVISIBLE (-400 1560);
WIRE 16 -1 (1150 1750)(1150 1650);
WIRE 16 -1 (1150 1750)(1725 1750);
FORCEPROP 0 LAST SIG_NAME FM_P12V_HOTSWAP0_EN
J 0
(1265 1760);
DISPLAY 0.617021 (1265 1760);
PAINT ORANGE (1265 1760);
WIRE 16 -1 (700 1650)(700 1750);
WIRE 16 -1 (1050 1750)(700 1750);
WIRE 16 -1 (1050 1750)(1150 1750);
WIRE 16 -1 (1050 1800)(1050 1750);
WIRE 16 -1 (725 2550)(1675 2550);
FORCEPROP 2 LAST SIG_NAME P3E_CPU1_PE3_MP_C_TXP<2>
J 0
(915 2560);
DISPLAY 0.617021 (915 2560);
PAINT ORANGE (915 2560);
FORCEPROP 2 LASTPROP $XRERR UNIQUE?
J 0
(675 2560);
DISPLAY 0.638298 (675 2560);
PAINT MONO (675 2560);
DISPLAY INVISIBLE (675 2560);
WIRE 16 -1 (725 2600)(2175 2600);
FORCEPROP 2 LAST SIG_NAME P3E_CPU1_PE3_MP_C_TXN<2>
J 0
(915 2610);
DISPLAY 0.617021 (915 2610);
PAINT ORANGE (915 2610);
FORCEPROP 2 LASTPROP $XRERR UNIQUE?
J 0
(675 2610);
DISPLAY 0.638298 (675 2610);
PAINT MONO (675 2610);
DISPLAY INVISIBLE (675 2610);
WIRE 16 -1 (-925 2700)(-1400 2700);
WIRE 16 -1 (-525 2700)(-925 2700);
WIRE 16 -1 (-925 2175)(-925 2700);
WIRE 16 -1 (-2825 2175)(-925 2175);
FORCEPROP 2 LAST SIG_NAME FAN_PWM_OUT_SYS0_R1
J 0
(-2710 2185);
DISPLAY 0.617021 (-2710 2185);
PAINT ORANGE (-2710 2185);
WIRE 16 -1 (50 875)(300 875);
WIRE 16 -1 (300 875)(700 875);
WIRE 16 -1 (300 725)(300 875);
FORCEPROP 0 LAST SIG_NAME FM_PS_EN
J 0
(90 885);
DISPLAY 0.617021 (90 885);
PAINT ORANGE (90 885);
WIRE 16 -1 (725 4500)(1950 4500);
FORCEPROP 2 LAST SIG_NAME NIC_MDI_MNG_TX_DP
J 0
(1115 4510);
DISPLAY 0.617021 (1115 4510);
PAINT ORANGE (1115 4510);
WIRE 16 -1 (1950 4450)(725 4450);
FORCEPROP 2 LAST SIG_NAME NIC_MDI_MNG_TX_DN
J 0
(1115 4460);
DISPLAY 0.617021 (1115 4460);
PAINT ORANGE (1115 4460);
WIRE 16 -1 (725 4350)(1950 4350);
FORCEPROP 2 LAST SIG_NAME NIC_MDI_MNG_RX_DP
J 0
(1115 4360);
DISPLAY 0.617021 (1115 4360);
PAINT ORANGE (1115 4360);
WIRE 16 -1 (-525 4450)(-950 4450);
WIRE 16 -1 (-525 4350)(-1200 4350);
WIRE 16 -1 (-525 4200)(-950 4200);
WIRE 16 -1 (-525 4150)(-1200 4150);
WIRE 16 -1 (-3075 3550)(-2275 3550);
FORCEPROP 2 LAST SIG_NAME SP2_BMC_CM_UART_TX_R1
J 0
(-3035 3560);
DISPLAY 0.617021 (-3035 3560);
PAINT ORANGE (-3035 3560);
WIRE 16 -1 (-525 3600)(-1200 3600);
WIRE 16 -1 (1875 2550)(2875 2550);
WIRE 16 -1 (-525 3300)(-1200 3300);
WIRE 16 -1 (-525 3050)(-2325 3050);
FORCEPROP 0 LAST SIG_NAME FM_ENABLE_FAN_POWER
J 0
(-1310 3060);
DISPLAY 0.617021 (-1310 3060);
PAINT ORANGE (-1310 3060);
WIRE 16 -1 (-1675 3600)(-1450 3600);
WIRE 16 -1 (-1450 3150)(-1650 3150);
WIRE 16 -1 (-1450 3600)(-1450 3150);
WIRE 16 -1 (-525 3150)(-1450 3150);
FORCEPROP 0 LAST SIG_NAME SPA_MID_DBG_TX_R
J 0
(-1235 3160);
DISPLAY 0.617021 (-1235 3160);
PAINT ORANGE (-1235 3160);
FORCEPROP 2 LASTPROP $XRERR UNIQUE?
J 0
(-1475 3160);
DISPLAY 0.638298 (-1475 3160);
PAINT MONO (-1475 3160);
DISPLAY INVISIBLE (-1475 3160);
WIRE 16 -1 (-525 3250)(-950 3250);
WIRE 16 -1 (-525 3400)(-1200 3400);
WIRE 16 -1 (-525 3450)(-950 3450);
WIRE 16 -1 (-525 3950)(-1200 3950);
WIRE 16 -1 (-525 2550)(-1950 2550);
FORCEPROP 0 LAST SIG_NAME CLK_100M_AIRMAX8_PE1_DN
J 0
(-1910 2560);
DISPLAY 0.617021 (-1910 2560);
PAINT ORANGE (-1910 2560);
WIRE 16 -1 (-2850 2700)(-1600 2700);
FORCEPROP 2 LAST SIG_NAME FAN_PWM_OUT_SYS0_R
J 0
(-2785 2710);
DISPLAY 0.617021 (-2785 2710);
PAINT ORANGE (-2785 2710);
WIRE 16 -1 (-2875 2850)(-1625 2850);
FORCEPROP 2 LAST SIG_NAME FAN_TACH1
J 0
(-2810 2860);
DISPLAY 0.617021 (-2810 2860);
PAINT ORANGE (-2810 2860);
WIRE 16 -1 (-2875 2800)(-2325 2800);
FORCEPROP 2 LAST SIG_NAME FAN_TACH0
J 0
(-2810 2810);
DISPLAY 0.617021 (-2810 2810);
PAINT ORANGE (-2810 2810);
WIRE 3 2175 (-2375 3025)(-1350 3025);
WIRE 3 2175 (-1350 3950)(-1350 3025);
WIRE 3 2175 (-2375 3950)(-2375 3025);
WIRE 3 2175 (-2375 3950)(-1350 3950);
WIRE 16 -1 (-2025 3100)(-2000 3100);
WIRE 16 -1 (-2000 3100)(-525 3100);
FORCEPROP 0 LAST SIG_NAME SPA_MID_DBG_RX_R
J 0
(-1235 3110);
DISPLAY 0.617021 (-1235 3110);
PAINT ORANGE (-1235 3110);
FORCEPROP 2 LASTPROP $XRERR UNIQUE?
J 0
(-1475 3110);
DISPLAY 0.638298 (-1475 3110);
PAINT MONO (-1475 3110);
DISPLAY INVISIBLE (-1475 3110);
WIRE 16 -1 (-2075 3550)(-2000 3550);
WIRE 16 -1 (-2000 3550)(-2000 3100);
WIRE 16 -1 (-3050 3150)(-1850 3150);
FORCEPROP 2 LAST SIG_NAME SPA_MID_DBG_TX
J 0
(-3010 3160);
DISPLAY 0.617021 (-3010 3160);
PAINT ORANGE (-3010 3160);
WIRE 16 -1 (-3075 3600)(-1875 3600);
FORCEPROP 2 LAST SIG_NAME SP2_BMC_CM_UART_RX_R1
J 0
(-3035 3610);
DISPLAY 0.617021 (-3035 3610);
PAINT ORANGE (-3035 3610);
WIRE 16 -1 (-2875 2900)(-2325 2900);
FORCEPROP 2 LAST SIG_NAME FAN_TACH2
J 0
(-2810 2910);
DISPLAY 0.617021 (-2810 2910);
PAINT ORANGE (-2810 2910);
WIRE 16 -1 (1000 825)(1550 825);
FORCEPROP 0 LAST SIG_NAME FM_CTNR_PS_ON_R
J 0
(1065 835);
DISPLAY 0.617021 (1065 835);
PAINT ORANGE (1065 835);
FORCEPROP 2 LASTPROP $XRERR UNIQUE?
J 0
(825 835);
DISPLAY 0.638298 (825 835);
PAINT MONO (825 835);
DISPLAY INVISIBLE (825 835);
WIRE 16 -1 (2950 1300)(3900 1300);
FORCEPROP 2 LAST SIG_NAME FM_MP_PS_REDUNDANT_LOST_N
J 0
(2950 1310);
DISPLAY 0.617021 (2950 1310);
PAINT ORANGE (2950 1310);
WIRE 16 -1 (3225 1875)(2750 1875);
FORCEPROP 0 LAST SIG_NAME FM_MB_SLOT_ID2
J 0
(2915 1885);
DISPLAY 0.617021 (2915 1885);
PAINT ORANGE (2915 1885);
WIRE 16 -1 (-3050 3100)(-2225 3100);
FORCEPROP 2 LAST SIG_NAME SPA_MID_DBG_RX
J 0
(-3010 3110);
DISPLAY 0.617021 (-3010 3110);
PAINT ORANGE (-3010 3110);
WIRE 16 -1 (2750 2225)(3225 2225);
FORCEPROP 0 LAST SIG_NAME FM_MB_SLOT_ID0
J 0
(2915 2235);
DISPLAY 0.617021 (2915 2235);
PAINT ORANGE (2915 2235);
WIRE 16 -1 (-2875 2950)(-1625 2950);
FORCEPROP 2 LAST SIG_NAME FAN_TACH3
J 0
(-2810 2960);
DISPLAY 0.617021 (-2810 2960);
PAINT ORANGE (-2810 2960);
WIRE 16 -1 (2375 3300)(3125 3300);
WIRE 16 -1 (2375 3150)(2875 3150);
WIRE 16 -1 (2375 2600)(3125 2600);
WIRE 16 -1 (2375 2750)(3125 2750);
WIRE 16 -1 (1925 3250)(2875 3250);
WIRE 16 -1 (1925 3100)(3125 3100);
WIRE 16 -1 (1875 2850)(2875 2850);
WIRE 16 -1 (1875 2700)(2875 2700);
WIRE 16 -1 (-525 2600)(-1950 2600);
FORCEPROP 0 LAST SIG_NAME CLK_100M_AIRMAX8_PE1_DP
J 0
(-1910 2610);
DISPLAY 0.617021 (-1910 2610);
PAINT ORANGE (-1910 2610);
WIRE 16 -1 (-1950 2750)(-525 2750);
FORCEPROP 0 LAST SIG_NAME FM_MATED_IN_N
J 0
(-1910 2760);
DISPLAY 0.617021 (-1910 2760);
PAINT ORANGE (-1910 2760);
WIRE 16 -1 (-525 3750)(-950 3750);
WIRE 16 -1 (-525 3650)(-950 3650);
WIRE 16 -1 (-525 4300)(-950 4300);
WIRE 16 -1 (-525 4500)(-1200 4500);
WIRE 16 -1 (725 2750)(2175 2750);
FORCEPROP 2 LAST SIG_NAME P3E_CPU1_PE3_MP_C_TXN<1>
J 0
(915 2760);
DISPLAY 0.617021 (915 2760);
PAINT ORANGE (915 2760);
FORCEPROP 2 LASTPROP $XRERR UNIQUE?
J 0
(675 2760);
DISPLAY 0.638298 (675 2760);
PAINT MONO (675 2760);
DISPLAY INVISIBLE (675 2760);
WIRE 16 -1 (725 3100)(1725 3100);
FORCEPROP 2 LAST SIG_NAME P3E_CPU1_PE3_MP_C_TXN<5>
J 0
(915 3110);
DISPLAY 0.617021 (915 3110);
PAINT ORANGE (915 3110);
FORCEPROP 2 LASTPROP $XRERR UNIQUE?
J 0
(675 3110);
DISPLAY 0.638298 (675 3110);
PAINT MONO (675 3110);
DISPLAY INVISIBLE (675 3110);
WIRE 16 -1 (725 3300)(2175 3300);
FORCEPROP 2 LAST SIG_NAME P3E_CPU1_PE3_MP_C_TXN<4>
J 0
(915 3310);
DISPLAY 0.617021 (915 3310);
PAINT ORANGE (915 3310);
FORCEPROP 2 LASTPROP $XRERR UNIQUE?
J 0
(675 3310);
DISPLAY 0.638298 (675 3310);
PAINT MONO (675 3310);
DISPLAY INVISIBLE (675 3310);
WIRE 16 -1 (1725 3750)(725 3750);
FORCEPROP 2 LAST SIG_NAME P3E_CPU1_PE3_MP_C_TXP<6>
J 0
(915 3760);
DISPLAY 0.617021 (915 3760);
PAINT ORANGE (915 3760);
FORCEPROP 2 LASTPROP $XRERR UNIQUE?
J 0
(675 3760);
DISPLAY 0.638298 (675 3760);
PAINT MONO (675 3760);
DISPLAY INVISIBLE (675 3760);
WIRE 16 -1 (1950 4100)(725 4100);
FORCEPROP 2 LAST SIG_NAME RST_PCIE_MIDPLANE_N
J 0
(1090 4110);
DISPLAY 0.617021 (1090 4110);
PAINT ORANGE (1090 4110);
WIRE 16 -1 (725 2850)(1675 2850);
FORCEPROP 2 LAST SIG_NAME P3E_CPU1_PE3_MP_C_TXP<0>
J 0
(915 2860);
DISPLAY 0.617021 (915 2860);
PAINT ORANGE (915 2860);
FORCEPROP 2 LASTPROP $XRERR UNIQUE?
J 0
(675 2860);
DISPLAY 0.638298 (675 2860);
PAINT MONO (675 2860);
DISPLAY INVISIBLE (675 2860);
WIRE 16 -1 (725 3600)(1725 3600);
FORCEPROP 2 LAST SIG_NAME P3E_CPU1_PE3_MP_C_TXN<7>
J 0
(915 3610);
DISPLAY 0.617021 (915 3610);
PAINT ORANGE (915 3610);
FORCEPROP 2 LASTPROP $XRERR UNIQUE?
J 0
(675 3610);
DISPLAY 0.638298 (675 3610);
PAINT MONO (675 3610);
DISPLAY INVISIBLE (675 3610);
WIRE 16 -1 (1950 4150)(725 4150);
FORCEPROP 2 LAST SIG_NAME FM_MB_SLOT_ID2
J 0
(1315 4160);
DISPLAY 0.617021 (1315 4160);
PAINT ORANGE (1315 4160);
WIRE 16 -1 (725 4200)(1950 4200);
FORCEPROP 2 LAST SIG_NAME FM_MB_SLOT_ID1
J 0
(1315 4210);
DISPLAY 0.617021 (1315 4210);
PAINT ORANGE (1315 4210);
WIRE 16 -1 (725 4250)(1950 4250);
FORCEPROP 2 LAST SIG_NAME FM_MB_SLOT_ID0
J 0
(1315 4260);
DISPLAY 0.617021 (1315 4260);
PAINT ORANGE (1315 4260);
WIRE 16 -1 (1950 4300)(725 4300);
FORCEPROP 2 LAST SIG_NAME NIC_MDI_MNG_RX_DN
J 0
(1115 4310);
DISPLAY 0.617021 (1115 4310);
PAINT ORANGE (1115 4310);
WIRE 16 -1 (725 3150)(2175 3150);
FORCEPROP 2 LAST SIG_NAME P3E_CPU1_PE3_MP_C_TXP<5>
J 0
(915 3160);
DISPLAY 0.617021 (915 3160);
PAINT ORANGE (915 3160);
FORCEPROP 2 LASTPROP $XRERR UNIQUE?
J 0
(675 3160);
DISPLAY 0.638298 (675 3160);
PAINT MONO (675 3160);
DISPLAY INVISIBLE (675 3160);
WIRE 16 -1 (2175 2900)(725 2900);
FORCEPROP 2 LAST SIG_NAME P3E_CPU1_PE3_MP_C_TXN<0>
J 0
(915 2910);
DISPLAY 0.617021 (915 2910);
PAINT ORANGE (915 2910);
FORCEPROP 2 LASTPROP $XRERR UNIQUE?
J 0
(675 2910);
DISPLAY 0.638298 (675 2910);
PAINT MONO (675 2910);
DISPLAY INVISIBLE (675 2910);
WIRE 16 -1 (725 2700)(1675 2700);
FORCEPROP 2 LAST SIG_NAME P3E_CPU1_PE3_MP_C_TXP<1>
J 0
(915 2710);
DISPLAY 0.617021 (915 2710);
PAINT ORANGE (915 2710);
FORCEPROP 2 LASTPROP $XRERR UNIQUE?
J 0
(675 2710);
DISPLAY 0.638298 (675 2710);
PAINT MONO (675 2710);
DISPLAY INVISIBLE (675 2710);
WIRE 16 -1 (3125 2900)(2375 2900);
WIRE 16 -1 (725 3250)(1725 3250);
FORCEPROP 2 LAST SIG_NAME P3E_CPU1_PE3_MP_C_TXP<4>
J 0
(915 3260);
DISPLAY 0.617021 (915 3260);
PAINT ORANGE (915 3260);
FORCEPROP 2 LASTPROP $XRERR UNIQUE?
J 0
(675 3260);
DISPLAY 0.638298 (675 3260);
PAINT MONO (675 3260);
DISPLAY INVISIBLE (675 3260);
WIRE 16 -1 (1725 3400)(725 3400);
FORCEPROP 2 LAST SIG_NAME P3E_CPU1_PE3_MP_C_TXP<3>
J 0
(915 3410);
DISPLAY 0.617021 (915 3410);
PAINT ORANGE (915 3410);
FORCEPROP 2 LASTPROP $XRERR UNIQUE?
J 0
(675 3410);
DISPLAY 0.638298 (675 3410);
PAINT MONO (675 3410);
DISPLAY INVISIBLE (675 3410);
WIRE 16 -1 (-525 3900)(-950 3900);
WIRE 16 -1 (-525 3800)(-1200 3800);
WIRE 16 -1 (2350 3450)(3125 3450);
WIRE 16 -1 (1925 3600)(3125 3600);
WIRE 16 -1 (2350 3650)(2875 3650);
WIRE 16 -1 (2350 3800)(3125 3800);
WIRE 16 -1 (2875 3750)(1925 3750);
WIRE 16 -1 (700 775)(50 775);
FORCEPROP 0 LAST SIG_NAME PWRGD_P12V_HSC_DLY
J 0
(90 785);
DISPLAY 0.617021 (90 785);
PAINT ORANGE (90 785);
WIRE 16 -1 (2275 825)(1750 825);
FORCEPROP 0 LAST SIG_NAME FM_CTNR_PS_ON
J 0
(1890 835);
DISPLAY 0.617021 (1890 835);
PAINT ORANGE (1890 835);
WIRE 16 -1 (2875 3400)(1925 3400);
WIRE 16 -1 (725 3450)(2150 3450);
FORCEPROP 2 LAST SIG_NAME P3E_CPU1_PE3_MP_C_TXN<3>
J 0
(915 3460);
DISPLAY 0.617021 (915 3460);
PAINT ORANGE (915 3460);
FORCEPROP 2 LASTPROP $XRERR UNIQUE?
J 0
(675 3460);
DISPLAY 0.638298 (675 3460);
PAINT MONO (675 3460);
DISPLAY INVISIBLE (675 3460);
WIRE 16 -1 (725 3650)(2150 3650);
FORCEPROP 2 LAST SIG_NAME P3E_CPU1_PE3_MP_C_TXP<7>
J 0
(915 3660);
DISPLAY 0.617021 (915 3660);
PAINT ORANGE (915 3660);
FORCEPROP 2 LASTPROP $XRERR UNIQUE?
J 0
(675 3660);
DISPLAY 0.638298 (675 3660);
PAINT MONO (675 3660);
DISPLAY INVISIBLE (675 3660);
WIRE 16 -1 (725 3800)(2150 3800);
FORCEPROP 2 LAST SIG_NAME P3E_CPU1_PE3_MP_C_TXN<6>
J 0
(915 3810);
DISPLAY 0.617021 (915 3810);
PAINT ORANGE (915 3810);
FORCEPROP 2 LASTPROP $XRERR UNIQUE?
J 0
(675 3810);
DISPLAY 0.638298 (675 3810);
PAINT MONO (675 3810);
DISPLAY INVISIBLE (675 3810);
WIRE 16 -1 (725 3900)(2300 3900);
FORCEPROP 2 LAST SIG_NAME SMB_BMC_PMBUS_STBY_LVC3_SCL
J 0
(1090 3910);
DISPLAY 0.617021 (1090 3910);
PAINT ORANGE (1090 3910);
WIRE 16 -1 (725 3950)(1950 3950);
FORCEPROP 2 LAST SIG_NAME SMB_BMC_PMBUS_STBY_LVC3_SDA
J 0
(1090 3960);
DISPLAY 0.617021 (1090 3960);
PAINT ORANGE (1090 3960);
WIRE 16 -1 (725 4000)(1950 4000);
FORCEPROP 2 LAST SIG_NAME IRQ_SML1_PMBUS_ALERT_R_N
J 0
(1090 4010);
DISPLAY 0.617021 (1090 4010);
PAINT ORANGE (1090 4010);
DOT 1 (2325 2050);
DOT 1 (1150 1750);
DOT 1 (-750 3550);
DOT 1 (900 3050);
DOT 1 (900 2950);
DOT 1 (900 2650);
DOT 1 (900 3200);
DOT 1 (900 3350);
DOT 1 (900 3550);
DOT 1 (900 3700);
DOT 1 (900 3850);
DOT 1 (900 2500);
DOT 1 (-2000 3100);
DOT 1 (-1450 3150);
DOT 1 (300 875);
DOT 1 (-975 2800);
DOT 1 (-925 2700);
DOT 1 (-750 2500);
DOT 1 (-750 2650);
DOT 1 (-1125 2950);
DOT 1 (-1075 2900);
DOT 1 (-1025 2850);
DOT 1 (-750 3200);
DOT 1 (-750 3700);
DOT 1 (-750 3850);
DOT 1 (-750 4000);
DOT 1 (-750 4250);
DOT 1 (1050 1750);
DOT 1 (2325 2225);
DOT 1 (-750 4100);
DOT 1 (900 2800);
DOT 1 (-750 3350);
DOT 1 (-2200 1550);
FORCENOTE
TP FAB4 DELETE 3PIN JUMPER J9W1 20170109
(-2700 825) 0;
DISPLAY LEFT (-2700 825);
DISPLAY 0.638298 (-2700 825);
PAINT RED (-2700 825);
FORCENOTE
TP FAB3-DVT DELETE 0OHM R9T8 20170103
(-2700 975) 0;
DISPLAY LEFT (-2700 975);
DISPLAY 0.638298 (-2700 975);
PAINT RED (-2700 975);
FORCENOTE
NOPOP R9F63,R9F70 1123
(-2100 3775) 0;
DISPLAY LEFT (-2100 3775);
DISPLAY 1.021277 (-2100 3775);
PAINT RED (-2100 3775);
FORCENOTE
TP FAB1 POP R9F64 R9F67
(-2350 3850) 0;
DISPLAY LEFT (-2350 3850);
DISPLAY 1.021277 (-2350 3850);
PAINT RED (-2350 3850);
FORCENOTE
TP FAB1 CHANGE SYMBOL TO ZZ.82092.07601 0310
(-475 4825) 0;
DISPLAY LEFT (-475 4825);
DISPLAY 1.021277 (-475 4825);
PAINT RED (-475 4825);
FORCENOTE
ROOM: IO_SLOT
(-3300 300) 0;
DISPLAY LEFT (-3300 300);
DISPLAY 1.021277 (-3300 300);
PAINT PURPLE (-3300 300);
FORCENOTE
BOM_COST:IO_SLOT
(-3300 250) 0;
DISPLAY LEFT (-3300 250);
DISPLAY 1.021277 (-3300 250);
PAINT PURPLE (-3300 250);
FORCENOTE
TP FAB1 POP 0OHM 1120
(-2700 1025) 0;
DISPLAY LEFT (-2700 1025);
DISPLAY 0.638298 (-2700 1025);
PAINT RED (-2700 1025);
FORCENOTE
TP FAB3-DVT ADD 3PIN JUMPER J9W1 20170103
(-2700 925) 0;
DISPLAY LEFT (-2700 925);
DISPLAY 0.638298 (-2700 925);
PAINT RED (-2700 925);
FORCENOTE
TP FAB4 ADD 0OHM R9T8 20170109
(-2700 875) 0;
DISPLAY LEFT (-2700 875);
DISPLAY 0.638298 (-2700 875);
PAINT RED (-2700 875);
FORCENOTE
TP FAB4 NOPOP J1F3 20170206
(3700 800) 0;
DISPLAY LEFT (3700 800);
DISPLAY 0.638298 (3700 800);
PAINT RED (3700 800);
QUIT
